FILE_TYPE = MACRO_DRAWING;
SET COLOR_WIRE YELLOW;
SET COLOR_PROP MONO;
SET COLOR_DOT WHITE;
SET COLOR_ARC YELLOW;
SET COLOR_BODY GREEN;
SET COLOR_NOTE MONO;
SET PROP_DISPLAY VALUE;
SET PAGE_NUMBER P109;
FORCEADD OFFPAGE..5
(-3500 1950);
FORCEPROP 2 LAST $XR1 121 
J 0
(-3875 1950);
DISPLAY 0.638298 (-3875 1950);
PAINT MONO (-3875 1950);
FORCEPROP 2 LAST $XR0 133 
J 0
(-3755 1950);
DISPLAY 0.638298 (-3755 1950);
PAINT MONO (-3755 1950);
FORCEPROP 2 LAST PATH I1
J 0
(-3750 2000);
DISPLAY 1.021277 (-3750 2000);
PAINT ORANGE (-3750 2000);
DISPLAY INVISIBLE (-3750 2000);
FORCEPROP 2 LAST CDS_LIB mstr_standard
J 0
(-3500 1950);
PAINT MONO (-3500 1950);
DISPLAY INVISIBLE (-3500 1950);
FORCEPROP 1 LAST OFFPAGE TRUE
J 0
(-3175 1825);
DISPLAY 0.872340 (-3175 1825);
PAINT GREEN (-3175 1825);
DISPLAY INVISIBLE (-3175 1825);
FORCEPROP 1 LAST COMMENT_BODY TRUE
J 0
(-3400 1875);
DISPLAY 0.872340 (-3400 1875);
PAINT GREEN (-3400 1875);
DISPLAY INVISIBLE (-3400 1875);
FORCEADD TAP..1
R 2
(-2050 2350);
FORCEPROP 3 LASTPIN (-2000 2350) SIG_NAME P3E_CPU0_PE2_SS_C_TXP<5>
J 0
(-1990 2360);
DISPLAY 0.659574 (-1990 2360);
PAINT MONO (-1990 2360);
DISPLAY INVISIBLE (-1990 2360);
FORCEPROP 1 LASTPIN (-2000 2350) BN 5
J 2
(-1988 2358);
DISPLAY 0.617021 (-1988 2358);
PAINT GREEN (-1988 2358);
FORCEPROP 2 LAST CDS_LIB mstr_standard
J 0
(-2050 2350);
PAINT MONO (-2050 2350);
DISPLAY INVISIBLE (-2050 2350);
FORCEPROP 1 LAST PATH I10
J 2
(-2048 2350);
DISPLAY 0.872340 (-2048 2350);
PAINT GREEN (-2048 2350);
DISPLAY INVISIBLE (-2048 2350);
FORCEPROP 1 LAST BODY_TYPE PLUMBING
J 2
(-2050 2400);
DISPLAY 0.872340 (-2050 2400);
PAINT GREEN (-2050 2400);
DISPLAY INVISIBLE (-2050 2400);
FORCEPROP 1 LAST HDL_TAP TRUE
J 2
(-2375 2225);
DISPLAY 0.872340 (-2375 2225);
PAINT ORANGE (-2375 2225);
DISPLAY INVISIBLE (-2375 2225);
FORCEADD TAP..1
R 2
(-2300 2400);
FORCEPROP 3 LASTPIN (-2250 2400) SIG_NAME P3E_CPU0_PE2_SS_C_TXN<5>
J 0
(-2240 2410);
DISPLAY 0.659574 (-2240 2410);
PAINT MONO (-2240 2410);
DISPLAY INVISIBLE (-2240 2410);
FORCEPROP 1 LASTPIN (-2250 2400) BN 5
J 2
(-2238 2408);
DISPLAY 0.617021 (-2238 2408);
PAINT GREEN (-2238 2408);
FORCEPROP 2 LAST CDS_LIB mstr_standard
J 0
(-2300 2400);
PAINT MONO (-2300 2400);
DISPLAY INVISIBLE (-2300 2400);
FORCEPROP 1 LAST PATH I11
J 2
(-2298 2400);
DISPLAY 0.872340 (-2298 2400);
PAINT GREEN (-2298 2400);
DISPLAY INVISIBLE (-2298 2400);
FORCEPROP 1 LAST BODY_TYPE PLUMBING
J 2
(-2300 2450);
DISPLAY 0.872340 (-2300 2450);
PAINT GREEN (-2300 2450);
DISPLAY INVISIBLE (-2300 2450);
FORCEPROP 1 LAST HDL_TAP TRUE
J 2
(-2625 2275);
DISPLAY 0.872340 (-2625 2275);
PAINT ORANGE (-2625 2275);
DISPLAY INVISIBLE (-2625 2275);
FORCEADD TAP..1
R 2
(-2300 2550);
FORCEPROP 3 LASTPIN (-2250 2550) SIG_NAME P3E_CPU0_PE2_SS_C_TXN<4>
J 0
(-2240 2560);
DISPLAY 0.659574 (-2240 2560);
PAINT MONO (-2240 2560);
DISPLAY INVISIBLE (-2240 2560);
FORCEPROP 1 LASTPIN (-2250 2550) BN 4
J 2
(-2238 2558);
DISPLAY 0.617021 (-2238 2558);
PAINT GREEN (-2238 2558);
FORCEPROP 2 LAST CDS_LIB mstr_standard
J 0
(-2300 2550);
PAINT MONO (-2300 2550);
DISPLAY INVISIBLE (-2300 2550);
FORCEPROP 1 LAST PATH I12
J 2
(-2298 2550);
DISPLAY 0.872340 (-2298 2550);
PAINT GREEN (-2298 2550);
DISPLAY INVISIBLE (-2298 2550);
FORCEPROP 1 LAST BODY_TYPE PLUMBING
J 2
(-2300 2600);
DISPLAY 0.872340 (-2300 2600);
PAINT GREEN (-2300 2600);
DISPLAY INVISIBLE (-2300 2600);
FORCEPROP 1 LAST HDL_TAP TRUE
J 2
(-2625 2425);
DISPLAY 0.872340 (-2625 2425);
PAINT ORANGE (-2625 2425);
DISPLAY INVISIBLE (-2625 2425);
FORCEADD TAP..1
R 2
(-2300 2700);
FORCEPROP 3 LASTPIN (-2250 2700) SIG_NAME P3E_CPU0_PE2_SS_C_TXN<3>
J 0
(-2240 2710);
DISPLAY 0.659574 (-2240 2710);
PAINT MONO (-2240 2710);
DISPLAY INVISIBLE (-2240 2710);
FORCEPROP 1 LASTPIN (-2250 2700) BN 3
J 2
(-2238 2708);
DISPLAY 0.617021 (-2238 2708);
PAINT GREEN (-2238 2708);
FORCEPROP 2 LAST CDS_LIB mstr_standard
J 0
(-2300 2700);
PAINT MONO (-2300 2700);
DISPLAY INVISIBLE (-2300 2700);
FORCEPROP 1 LAST PATH I13
J 2
(-2298 2700);
DISPLAY 0.872340 (-2298 2700);
PAINT GREEN (-2298 2700);
DISPLAY INVISIBLE (-2298 2700);
FORCEPROP 1 LAST BODY_TYPE PLUMBING
J 2
(-2300 2750);
DISPLAY 0.872340 (-2300 2750);
PAINT GREEN (-2300 2750);
DISPLAY INVISIBLE (-2300 2750);
FORCEPROP 1 LAST HDL_TAP TRUE
J 2
(-2625 2575);
DISPLAY 0.872340 (-2625 2575);
PAINT ORANGE (-2625 2575);
DISPLAY INVISIBLE (-2625 2575);
FORCEADD TAP..1
R 2
(-2300 2850);
FORCEPROP 3 LASTPIN (-2250 2850) SIG_NAME P3E_CPU0_PE2_SS_C_TXN<2>
J 0
(-2240 2860);
DISPLAY 0.659574 (-2240 2860);
PAINT MONO (-2240 2860);
DISPLAY INVISIBLE (-2240 2860);
FORCEPROP 1 LASTPIN (-2250 2850) BN 2
J 2
(-2238 2858);
DISPLAY 0.617021 (-2238 2858);
PAINT GREEN (-2238 2858);
FORCEPROP 2 LAST CDS_LIB mstr_standard
J 0
(-2300 2850);
PAINT MONO (-2300 2850);
DISPLAY INVISIBLE (-2300 2850);
FORCEPROP 1 LAST PATH I14
J 2
(-2298 2850);
DISPLAY 0.872340 (-2298 2850);
PAINT GREEN (-2298 2850);
DISPLAY INVISIBLE (-2298 2850);
FORCEPROP 1 LAST BODY_TYPE PLUMBING
J 2
(-2300 2900);
DISPLAY 0.872340 (-2300 2900);
PAINT GREEN (-2300 2900);
DISPLAY INVISIBLE (-2300 2900);
FORCEPROP 1 LAST HDL_TAP TRUE
J 2
(-2625 2725);
DISPLAY 0.872340 (-2625 2725);
PAINT ORANGE (-2625 2725);
DISPLAY INVISIBLE (-2625 2725);
FORCEADD TAP..1
R 2
(-2300 2950);
FORCEPROP 3 LASTPIN (-2250 2950) SIG_NAME P3E_CPU0_PE2_SS_C_TXN<1>
J 0
(-2240 2960);
DISPLAY 0.659574 (-2240 2960);
PAINT MONO (-2240 2960);
DISPLAY INVISIBLE (-2240 2960);
FORCEPROP 1 LASTPIN (-2250 2950) BN 1
J 2
(-2238 2958);
DISPLAY 0.617021 (-2238 2958);
PAINT GREEN (-2238 2958);
FORCEPROP 2 LAST CDS_LIB mstr_standard
J 0
(-2300 2950);
PAINT MONO (-2300 2950);
DISPLAY INVISIBLE (-2300 2950);
FORCEPROP 1 LAST PATH I15
J 2
(-2298 2950);
DISPLAY 0.872340 (-2298 2950);
PAINT GREEN (-2298 2950);
DISPLAY INVISIBLE (-2298 2950);
FORCEPROP 1 LAST BODY_TYPE PLUMBING
J 2
(-2300 3000);
DISPLAY 0.872340 (-2300 3000);
PAINT GREEN (-2300 3000);
DISPLAY INVISIBLE (-2300 3000);
FORCEPROP 1 LAST HDL_TAP TRUE
J 2
(-2625 2825);
DISPLAY 0.872340 (-2625 2825);
PAINT ORANGE (-2625 2825);
DISPLAY INVISIBLE (-2625 2825);
FORCEADD TAP..1
R 2
(-2300 3150);
FORCEPROP 3 LASTPIN (-2250 3150) SIG_NAME P3E_CPU0_PE2_SS_C_TXN<0>
J 0
(-2240 3160);
DISPLAY 0.659574 (-2240 3160);
PAINT MONO (-2240 3160);
DISPLAY INVISIBLE (-2240 3160);
FORCEPROP 1 LASTPIN (-2250 3150) BN 0
J 2
(-2238 3158);
DISPLAY 0.617021 (-2238 3158);
PAINT GREEN (-2238 3158);
FORCEPROP 2 LAST CDS_LIB mstr_standard
J 0
(-2300 3150);
PAINT MONO (-2300 3150);
DISPLAY INVISIBLE (-2300 3150);
FORCEPROP 1 LAST PATH I16
J 2
(-2298 3150);
DISPLAY 0.872340 (-2298 3150);
PAINT GREEN (-2298 3150);
DISPLAY INVISIBLE (-2298 3150);
FORCEPROP 1 LAST BODY_TYPE PLUMBING
J 2
(-2475 3200);
DISPLAY 0.872340 (-2475 3200);
PAINT GREEN (-2475 3200);
DISPLAY INVISIBLE (-2475 3200);
FORCEPROP 1 LAST HDL_TAP TRUE
J 2
(-2800 3025);
DISPLAY 0.872340 (-2800 3025);
PAINT ORANGE (-2800 3025);
DISPLAY INVISIBLE (-2800 3025);
FORCEADD TAP..1
R 2
(-2300 3250);
FORCEPROP 3 LASTPIN (-2250 3250) SIG_NAME P3E_CPU0_PE1_SS_C_TXP<0>
J 0
(-2240 3260);
DISPLAY 0.659574 (-2240 3260);
PAINT MONO (-2240 3260);
DISPLAY INVISIBLE (-2240 3260);
FORCEPROP 1 LASTPIN (-2250 3250) BN 0
J 2
(-2238 3258);
DISPLAY 0.617021 (-2238 3258);
PAINT GREEN (-2238 3258);
FORCEPROP 2 LAST CDS_LIB mstr_standard
J 0
(-2300 3250);
PAINT MONO (-2300 3250);
DISPLAY INVISIBLE (-2300 3250);
FORCEPROP 1 LAST PATH I17
J 2
(-2298 3250);
DISPLAY 0.872340 (-2298 3250);
PAINT GREEN (-2298 3250);
DISPLAY INVISIBLE (-2298 3250);
FORCEPROP 1 LAST BODY_TYPE PLUMBING
J 2
(-2300 3300);
DISPLAY 0.872340 (-2300 3300);
PAINT GREEN (-2300 3300);
DISPLAY INVISIBLE (-2300 3300);
FORCEPROP 1 LAST HDL_TAP TRUE
J 2
(-2625 3125);
DISPLAY 0.872340 (-2625 3125);
PAINT ORANGE (-2625 3125);
DISPLAY INVISIBLE (-2625 3125);
FORCEADD TAP..1
R 2
(-2050 2650);
FORCEPROP 3 LASTPIN (-2000 2650) SIG_NAME P3E_CPU0_PE2_SS_C_TXP<3>
J 0
(-1990 2660);
DISPLAY 0.659574 (-1990 2660);
PAINT MONO (-1990 2660);
DISPLAY INVISIBLE (-1990 2660);
FORCEPROP 1 LASTPIN (-2000 2650) BN 3
J 2
(-1988 2658);
DISPLAY 0.617021 (-1988 2658);
PAINT GREEN (-1988 2658);
FORCEPROP 2 LAST CDS_LIB mstr_standard
J 0
(-2050 2650);
PAINT MONO (-2050 2650);
DISPLAY INVISIBLE (-2050 2650);
FORCEPROP 1 LAST PATH I18
J 2
(-2048 2650);
DISPLAY 0.872340 (-2048 2650);
PAINT GREEN (-2048 2650);
DISPLAY INVISIBLE (-2048 2650);
FORCEPROP 1 LAST BODY_TYPE PLUMBING
J 2
(-2050 2700);
DISPLAY 0.872340 (-2050 2700);
PAINT GREEN (-2050 2700);
DISPLAY INVISIBLE (-2050 2700);
FORCEPROP 1 LAST HDL_TAP TRUE
J 2
(-2375 2525);
DISPLAY 0.872340 (-2375 2525);
PAINT ORANGE (-2375 2525);
DISPLAY INVISIBLE (-2375 2525);
FORCEADD TAP..1
R 2
(-2050 2500);
FORCEPROP 3 LASTPIN (-2000 2500) SIG_NAME P3E_CPU0_PE2_SS_C_TXP<4>
J 0
(-1990 2510);
DISPLAY 0.659574 (-1990 2510);
PAINT MONO (-1990 2510);
DISPLAY INVISIBLE (-1990 2510);
FORCEPROP 1 LASTPIN (-2000 2500) BN 4
J 2
(-1988 2508);
DISPLAY 0.617021 (-1988 2508);
PAINT GREEN (-1988 2508);
FORCEPROP 2 LAST CDS_LIB mstr_standard
J 0
(-2050 2500);
PAINT MONO (-2050 2500);
DISPLAY INVISIBLE (-2050 2500);
FORCEPROP 1 LAST PATH I19
J 2
(-2048 2500);
DISPLAY 0.872340 (-2048 2500);
PAINT GREEN (-2048 2500);
DISPLAY INVISIBLE (-2048 2500);
FORCEPROP 1 LAST BODY_TYPE PLUMBING
J 2
(-2050 2550);
DISPLAY 0.872340 (-2050 2550);
PAINT GREEN (-2050 2550);
DISPLAY INVISIBLE (-2050 2550);
FORCEPROP 1 LAST HDL_TAP TRUE
J 2
(-2375 2375);
DISPLAY 0.872340 (-2375 2375);
PAINT ORANGE (-2375 2375);
DISPLAY INVISIBLE (-2375 2375);
FORCEADD OFFPAGE..1
(-3500 3100);
FORCEPROP 2 LAST $XR0 105 
J 0
(-3752 3100);
DISPLAY 0.638298 (-3752 3100);
PAINT MONO (-3752 3100);
FORCEPROP 2 LAST PATH I2
J 0
(-3750 3150);
DISPLAY 1.021277 (-3750 3150);
PAINT ORANGE (-3750 3150);
DISPLAY INVISIBLE (-3750 3150);
FORCEPROP 2 LAST CDS_LIB mstr_standard
J 2
(-3500 3100);
PAINT MONO (-3500 3100);
DISPLAY INVISIBLE (-3500 3100);
FORCEPROP 1 LAST OFFPAGE TRUE
J 0
(-3175 2975);
DISPLAY 0.872340 (-3175 2975);
PAINT GREEN (-3175 2975);
DISPLAY INVISIBLE (-3175 2975);
FORCEPROP 1 LAST COMMENT_BODY TRUE
J 0
(-3375 3000);
DISPLAY 0.872340 (-3375 3000);
PAINT GREEN (-3375 3000);
DISPLAY INVISIBLE (-3375 3000);
FORCEADD TAP..1
R 2
(-2050 2800);
FORCEPROP 3 LASTPIN (-2000 2800) SIG_NAME P3E_CPU0_PE2_SS_C_TXP<2>
J 0
(-1990 2810);
DISPLAY 0.659574 (-1990 2810);
PAINT MONO (-1990 2810);
DISPLAY INVISIBLE (-1990 2810);
FORCEPROP 1 LASTPIN (-2000 2800) BN 2
J 2
(-1988 2808);
DISPLAY 0.617021 (-1988 2808);
PAINT GREEN (-1988 2808);
FORCEPROP 2 LAST CDS_LIB mstr_standard
J 0
(-2050 2800);
PAINT MONO (-2050 2800);
DISPLAY INVISIBLE (-2050 2800);
FORCEPROP 1 LAST PATH I20
J 2
(-2048 2800);
DISPLAY 0.872340 (-2048 2800);
PAINT GREEN (-2048 2800);
DISPLAY INVISIBLE (-2048 2800);
FORCEPROP 1 LAST BODY_TYPE PLUMBING
J 2
(-2050 2850);
DISPLAY 0.872340 (-2050 2850);
PAINT GREEN (-2050 2850);
DISPLAY INVISIBLE (-2050 2850);
FORCEPROP 1 LAST HDL_TAP TRUE
J 2
(-2375 2675);
DISPLAY 0.872340 (-2375 2675);
PAINT ORANGE (-2375 2675);
DISPLAY INVISIBLE (-2375 2675);
FORCEADD TAP..1
R 2
(-2050 3000);
FORCEPROP 3 LASTPIN (-2000 3000) SIG_NAME P3E_CPU0_PE2_SS_C_TXP<1>
J 0
(-1990 3010);
DISPLAY 0.659574 (-1990 3010);
PAINT MONO (-1990 3010);
DISPLAY INVISIBLE (-1990 3010);
FORCEPROP 1 LASTPIN (-2000 3000) BN 1
J 2
(-1988 3008);
DISPLAY 0.617021 (-1988 3008);
PAINT GREEN (-1988 3008);
FORCEPROP 2 LAST CDS_LIB mstr_standard
J 0
(-2050 3000);
PAINT MONO (-2050 3000);
DISPLAY INVISIBLE (-2050 3000);
FORCEPROP 1 LAST PATH I21
J 2
(-2048 3000);
DISPLAY 0.872340 (-2048 3000);
PAINT GREEN (-2048 3000);
DISPLAY INVISIBLE (-2048 3000);
FORCEPROP 1 LAST BODY_TYPE PLUMBING
J 2
(-2050 3050);
DISPLAY 0.872340 (-2050 3050);
PAINT GREEN (-2050 3050);
DISPLAY INVISIBLE (-2050 3050);
FORCEPROP 1 LAST HDL_TAP TRUE
J 2
(-2375 2875);
DISPLAY 0.872340 (-2375 2875);
PAINT ORANGE (-2375 2875);
DISPLAY INVISIBLE (-2375 2875);
FORCEADD TAP..1
R 2
(-2050 3100);
FORCEPROP 3 LASTPIN (-2000 3100) SIG_NAME P3E_CPU0_PE2_SS_C_TXP<0>
J 0
(-1990 3110);
DISPLAY 0.659574 (-1990 3110);
PAINT MONO (-1990 3110);
DISPLAY INVISIBLE (-1990 3110);
FORCEPROP 1 LASTPIN (-2000 3100) BN 0
J 2
(-1988 3108);
DISPLAY 0.617021 (-1988 3108);
PAINT GREEN (-1988 3108);
FORCEPROP 2 LAST CDS_LIB mstr_standard
J 0
(-2050 3100);
PAINT MONO (-2050 3100);
DISPLAY INVISIBLE (-2050 3100);
FORCEPROP 1 LAST PATH I22
J 2
(-2048 3100);
DISPLAY 0.872340 (-2048 3100);
PAINT GREEN (-2048 3100);
DISPLAY INVISIBLE (-2048 3100);
FORCEPROP 1 LAST BODY_TYPE PLUMBING
J 2
(-2050 3150);
DISPLAY 0.872340 (-2050 3150);
PAINT GREEN (-2050 3150);
DISPLAY INVISIBLE (-2050 3150);
FORCEPROP 1 LAST HDL_TAP TRUE
J 2
(-2375 2975);
DISPLAY 0.872340 (-2375 2975);
PAINT ORANGE (-2375 2975);
DISPLAY INVISIBLE (-2375 2975);
FORCEADD TAP..1
R 2
(-2050 3300);
FORCEPROP 3 LASTPIN (-2000 3300) SIG_NAME P3E_CPU0_PE1_SS_C_TXN<0>
J 0
(-1990 3310);
DISPLAY 0.659574 (-1990 3310);
PAINT MONO (-1990 3310);
DISPLAY INVISIBLE (-1990 3310);
FORCEPROP 1 LASTPIN (-2000 3300) BN 0
J 2
(-1988 3308);
DISPLAY 0.617021 (-1988 3308);
PAINT GREEN (-1988 3308);
FORCEPROP 2 LAST CDS_LIB mstr_standard
J 0
(-2050 3300);
PAINT MONO (-2050 3300);
DISPLAY INVISIBLE (-2050 3300);
FORCEPROP 1 LAST PATH I23
J 2
(-2048 3300);
DISPLAY 0.872340 (-2048 3300);
PAINT GREEN (-2048 3300);
DISPLAY INVISIBLE (-2048 3300);
FORCEPROP 1 LAST BODY_TYPE PLUMBING
J 2
(-2050 3350);
DISPLAY 0.872340 (-2050 3350);
PAINT GREEN (-2050 3350);
DISPLAY INVISIBLE (-2050 3350);
FORCEPROP 1 LAST HDL_TAP TRUE
J 2
(-2375 3175);
DISPLAY 0.872340 (-2375 3175);
PAINT ORANGE (-2375 3175);
DISPLAY INVISIBLE (-2375 3175);
FORCEADD GND..1
(-1525 1700);
FORCEPROP 3 LASTPIN (-1525 1750) SIG_NAME GND\g
J 0
(-1515 1760);
DISPLAY 0.659574 (-1515 1760);
PAINT MONO (-1515 1760);
DISPLAY INVISIBLE (-1515 1760);
FORCEPROP 1 LAST SIZE 1B
J 0
(-1450 1650);
DISPLAY 0.872340 (-1450 1650);
PAINT AQUA (-1450 1650);
DISPLAY INVISIBLE (-1450 1650);
FORCEPROP 2 LAST CDS_LIB mstr_symbols
J 0
(-1525 1700);
PAINT MONO (-1525 1700);
DISPLAY INVISIBLE (-1525 1700);
FORCEPROP 1 LAST VOLTAGE 0
J 0
(-1525 1700);
PAINT SKYBLUE (-1525 1700);
DISPLAY INVISIBLE (-1525 1700);
FORCEPROP 1 LAST PATH I25
J 0
(-1450 1700);
DISPLAY 0.872340 (-1450 1700);
PAINT AQUA (-1450 1700);
DISPLAY INVISIBLE (-1450 1700);
FORCEPROP 1 LAST BODY_TYPE PLUMBING
J 0
(-1570 1657);
DISPLAY 0.340426 (-1570 1657);
PAINT GREEN (-1570 1657);
DISPLAY INVISIBLE (-1570 1657);
FORCEPROP 1 LAST HDL_POWER GND
J 0
(-1525 1850);
DISPLAY 0.872340 (-1525 1850);
PAINT GREEN (-1525 1850);
DISPLAY INVISIBLE (-1525 1850);
FORCEADD GND..1
(-475 1700);
FORCEPROP 3 LASTPIN (-475 1750) SIG_NAME GND\g
J 0
(-465 1760);
DISPLAY 0.659574 (-465 1760);
PAINT MONO (-465 1760);
DISPLAY INVISIBLE (-465 1760);
FORCEPROP 2 LAST CDS_LIB mstr_symbols
J 0
(-475 1700);
PAINT MONO (-475 1700);
DISPLAY INVISIBLE (-475 1700);
FORCEPROP 1 LAST SIZE 1B
J 0
(-400 1650);
DISPLAY 0.872340 (-400 1650);
PAINT AQUA (-400 1650);
DISPLAY INVISIBLE (-400 1650);
FORCEPROP 1 LAST VOLTAGE 0
J 0
(-475 1700);
PAINT SKYBLUE (-475 1700);
DISPLAY INVISIBLE (-475 1700);
FORCEPROP 1 LAST PATH I26
J 0
(-400 1700);
DISPLAY 0.872340 (-400 1700);
PAINT AQUA (-400 1700);
DISPLAY INVISIBLE (-400 1700);
FORCEPROP 1 LAST BODY_TYPE PLUMBING
J 0
(-520 1657);
DISPLAY 0.340426 (-520 1657);
PAINT GREEN (-520 1657);
DISPLAY INVISIBLE (-520 1657);
FORCEPROP 1 LAST HDL_POWER GND
J 0
(-475 1850);
DISPLAY 0.872340 (-475 1850);
PAINT GREEN (-475 1850);
DISPLAY INVISIBLE (-475 1850);
FORCEADD TAP..1
(-275 2050);
FORCEPROP 3 LASTPIN (-325 2050) SIG_NAME P3E_CPU0_PE2_SS_RXN<7>
J 0
(-315 2060);
DISPLAY 0.659574 (-315 2060);
PAINT MONO (-315 2060);
DISPLAY INVISIBLE (-315 2060);
FORCEPROP 1 LASTPIN (-325 2050) BN 7
J 0
(-337 2058);
DISPLAY 0.617021 (-337 2058);
PAINT GREEN (-337 2058);
FORCEPROP 2 LAST CDS_LIB mstr_standard
J 0
(-275 2050);
PAINT MONO (-275 2050);
DISPLAY INVISIBLE (-275 2050);
FORCEPROP 1 LAST PATH I27
J 0
(-277 2050);
DISPLAY 0.872340 (-277 2050);
PAINT GREEN (-277 2050);
DISPLAY INVISIBLE (-277 2050);
FORCEPROP 1 LAST BODY_TYPE PLUMBING
J 0
(-100 2100);
DISPLAY 0.872340 (-100 2100);
PAINT GREEN (-100 2100);
DISPLAY INVISIBLE (-100 2100);
FORCEPROP 1 LAST HDL_TAP TRUE
J 0
(225 1925);
DISPLAY 0.872340 (225 1925);
PAINT ORANGE (225 1925);
DISPLAY INVISIBLE (225 1925);
FORCEADD TAP..1
(-275 2350);
FORCEPROP 3 LASTPIN (-325 2350) SIG_NAME P3E_CPU0_PE2_SS_RXN<5>
J 0
(-315 2360);
DISPLAY 0.659574 (-315 2360);
PAINT MONO (-315 2360);
DISPLAY INVISIBLE (-315 2360);
FORCEPROP 1 LASTPIN (-325 2350) BN 5
J 0
(-337 2358);
DISPLAY 0.617021 (-337 2358);
PAINT GREEN (-337 2358);
FORCEPROP 2 LAST CDS_LIB mstr_standard
J 0
(-275 2350);
PAINT MONO (-275 2350);
DISPLAY INVISIBLE (-275 2350);
FORCEPROP 1 LAST PATH I28
J 0
(-277 2350);
DISPLAY 0.872340 (-277 2350);
PAINT GREEN (-277 2350);
DISPLAY INVISIBLE (-277 2350);
FORCEPROP 1 LAST BODY_TYPE PLUMBING
J 0
(-100 2400);
DISPLAY 0.872340 (-100 2400);
PAINT GREEN (-100 2400);
DISPLAY INVISIBLE (-100 2400);
FORCEPROP 1 LAST HDL_TAP TRUE
J 0
(225 2225);
DISPLAY 0.872340 (225 2225);
PAINT ORANGE (225 2225);
DISPLAY INVISIBLE (225 2225);
FORCEADD TAP..1
(-275 2150);
FORCEPROP 3 LASTPIN (-325 2150) SIG_NAME P3E_CPU0_PE2_SS_RXN<6>
J 0
(-315 2160);
DISPLAY 0.659574 (-315 2160);
PAINT MONO (-315 2160);
DISPLAY INVISIBLE (-315 2160);
FORCEPROP 1 LASTPIN (-325 2150) BN 6
J 0
(-337 2158);
DISPLAY 0.617021 (-337 2158);
PAINT GREEN (-337 2158);
FORCEPROP 2 LAST CDS_LIB mstr_standard
J 0
(-275 2150);
PAINT MONO (-275 2150);
DISPLAY INVISIBLE (-275 2150);
FORCEPROP 1 LAST PATH I29
J 0
(-277 2150);
DISPLAY 0.872340 (-277 2150);
PAINT GREEN (-277 2150);
DISPLAY INVISIBLE (-277 2150);
FORCEPROP 1 LAST BODY_TYPE PLUMBING
J 0
(-100 2200);
DISPLAY 0.872340 (-100 2200);
PAINT GREEN (-100 2200);
DISPLAY INVISIBLE (-100 2200);
FORCEPROP 1 LAST HDL_TAP TRUE
J 0
(225 2025);
DISPLAY 0.872340 (225 2025);
PAINT ORANGE (225 2025);
DISPLAY INVISIBLE (225 2025);
FORCEADD OFFPAGE..1
(-3500 3200);
FORCEPROP 2 LAST $XR0 105 
J 0
(-3752 3200);
DISPLAY 0.638298 (-3752 3200);
PAINT MONO (-3752 3200);
FORCEPROP 2 LAST PATH I3
J 0
(-3750 3250);
DISPLAY 1.021277 (-3750 3250);
PAINT ORANGE (-3750 3250);
DISPLAY INVISIBLE (-3750 3250);
FORCEPROP 2 LAST CDS_LIB mstr_standard
J 2
(-3500 3200);
PAINT MONO (-3500 3200);
DISPLAY INVISIBLE (-3500 3200);
FORCEPROP 1 LAST OFFPAGE TRUE
J 0
(-3175 3075);
DISPLAY 0.872340 (-3175 3075);
PAINT GREEN (-3175 3075);
DISPLAY INVISIBLE (-3175 3075);
FORCEPROP 1 LAST COMMENT_BODY TRUE
J 0
(-3375 3100);
DISPLAY 0.872340 (-3375 3100);
PAINT GREEN (-3375 3100);
DISPLAY INVISIBLE (-3375 3100);
FORCEADD TAP..1
(-50 2000);
FORCEPROP 3 LASTPIN (-100 2000) SIG_NAME P3E_CPU0_PE2_SS_RXP<7>
J 0
(-90 2010);
DISPLAY 0.659574 (-90 2010);
PAINT MONO (-90 2010);
DISPLAY INVISIBLE (-90 2010);
FORCEPROP 1 LASTPIN (-100 2000) BN 7
J 0
(-112 2008);
DISPLAY 0.617021 (-112 2008);
PAINT GREEN (-112 2008);
FORCEPROP 2 LAST CDS_LIB mstr_standard
J 0
(-50 2000);
PAINT MONO (-50 2000);
DISPLAY INVISIBLE (-50 2000);
FORCEPROP 1 LAST PATH I30
J 0
(-52 2000);
DISPLAY 0.872340 (-52 2000);
PAINT GREEN (-52 2000);
DISPLAY INVISIBLE (-52 2000);
FORCEPROP 1 LAST BODY_TYPE PLUMBING
J 0
(125 2050);
DISPLAY 0.872340 (125 2050);
PAINT GREEN (125 2050);
DISPLAY INVISIBLE (125 2050);
FORCEPROP 1 LAST HDL_TAP TRUE
J 0
(450 1875);
DISPLAY 0.872340 (450 1875);
PAINT ORANGE (450 1875);
DISPLAY INVISIBLE (450 1875);
FORCEADD TAP..1
(-50 2300);
FORCEPROP 3 LASTPIN (-100 2300) SIG_NAME P3E_CPU0_PE2_SS_RXP<5>
J 0
(-90 2310);
DISPLAY 0.659574 (-90 2310);
PAINT MONO (-90 2310);
DISPLAY INVISIBLE (-90 2310);
FORCEPROP 1 LASTPIN (-100 2300) BN 5
J 0
(-112 2308);
DISPLAY 0.617021 (-112 2308);
PAINT GREEN (-112 2308);
FORCEPROP 2 LAST CDS_LIB mstr_standard
J 0
(-50 2300);
PAINT MONO (-50 2300);
DISPLAY INVISIBLE (-50 2300);
FORCEPROP 1 LAST PATH I31
J 0
(-52 2300);
DISPLAY 0.872340 (-52 2300);
PAINT GREEN (-52 2300);
DISPLAY INVISIBLE (-52 2300);
FORCEPROP 1 LAST BODY_TYPE PLUMBING
J 0
(125 2350);
DISPLAY 0.872340 (125 2350);
PAINT GREEN (125 2350);
DISPLAY INVISIBLE (125 2350);
FORCEPROP 1 LAST HDL_TAP TRUE
J 0
(450 2175);
DISPLAY 0.872340 (450 2175);
PAINT ORANGE (450 2175);
DISPLAY INVISIBLE (450 2175);
FORCEADD TAP..1
(-50 2200);
FORCEPROP 3 LASTPIN (-100 2200) SIG_NAME P3E_CPU0_PE2_SS_RXP<6>
J 0
(-90 2210);
DISPLAY 0.659574 (-90 2210);
PAINT MONO (-90 2210);
DISPLAY INVISIBLE (-90 2210);
FORCEPROP 1 LASTPIN (-100 2200) BN 6
J 0
(-112 2208);
DISPLAY 0.617021 (-112 2208);
PAINT GREEN (-112 2208);
FORCEPROP 2 LAST CDS_LIB mstr_standard
J 0
(-50 2200);
PAINT MONO (-50 2200);
DISPLAY INVISIBLE (-50 2200);
FORCEPROP 1 LAST PATH I32
J 0
(-52 2200);
DISPLAY 0.872340 (-52 2200);
PAINT GREEN (-52 2200);
DISPLAY INVISIBLE (-52 2200);
FORCEPROP 1 LAST BODY_TYPE PLUMBING
J 0
(125 2250);
DISPLAY 0.872340 (125 2250);
PAINT GREEN (125 2250);
DISPLAY INVISIBLE (125 2250);
FORCEPROP 1 LAST HDL_TAP TRUE
J 0
(450 2075);
DISPLAY 0.872340 (450 2075);
PAINT ORANGE (450 2075);
DISPLAY INVISIBLE (450 2075);
FORCEADD TAP..1
(-275 2500);
FORCEPROP 3 LASTPIN (-325 2500) SIG_NAME P3E_CPU0_PE2_SS_RXN<4>
J 0
(-315 2510);
DISPLAY 0.659574 (-315 2510);
PAINT MONO (-315 2510);
DISPLAY INVISIBLE (-315 2510);
FORCEPROP 1 LASTPIN (-325 2500) BN 4
J 0
(-337 2508);
DISPLAY 0.617021 (-337 2508);
PAINT GREEN (-337 2508);
FORCEPROP 2 LAST CDS_LIB mstr_standard
J 0
(-275 2500);
PAINT MONO (-275 2500);
DISPLAY INVISIBLE (-275 2500);
FORCEPROP 1 LAST PATH I33
J 0
(-277 2500);
DISPLAY 0.872340 (-277 2500);
PAINT GREEN (-277 2500);
DISPLAY INVISIBLE (-277 2500);
FORCEPROP 1 LAST BODY_TYPE PLUMBING
J 0
(-100 2550);
DISPLAY 0.872340 (-100 2550);
PAINT GREEN (-100 2550);
DISPLAY INVISIBLE (-100 2550);
FORCEPROP 1 LAST HDL_TAP TRUE
J 0
(225 2375);
DISPLAY 0.872340 (225 2375);
PAINT ORANGE (225 2375);
DISPLAY INVISIBLE (225 2375);
FORCEADD TAP..1
(-275 2650);
FORCEPROP 3 LASTPIN (-325 2650) SIG_NAME P3E_CPU0_PE2_SS_RXN<3>
J 0
(-315 2660);
DISPLAY 0.659574 (-315 2660);
PAINT MONO (-315 2660);
DISPLAY INVISIBLE (-315 2660);
FORCEPROP 1 LASTPIN (-325 2650) BN 3
J 0
(-337 2658);
DISPLAY 0.617021 (-337 2658);
PAINT GREEN (-337 2658);
FORCEPROP 2 LAST CDS_LIB mstr_standard
J 0
(-275 2650);
PAINT MONO (-275 2650);
DISPLAY INVISIBLE (-275 2650);
FORCEPROP 1 LAST PATH I34
J 0
(-277 2650);
DISPLAY 0.872340 (-277 2650);
PAINT GREEN (-277 2650);
DISPLAY INVISIBLE (-277 2650);
FORCEPROP 1 LAST BODY_TYPE PLUMBING
J 0
(-100 2700);
DISPLAY 0.872340 (-100 2700);
PAINT GREEN (-100 2700);
DISPLAY INVISIBLE (-100 2700);
FORCEPROP 1 LAST HDL_TAP TRUE
J 0
(225 2525);
DISPLAY 0.872340 (225 2525);
PAINT ORANGE (225 2525);
DISPLAY INVISIBLE (225 2525);
FORCEADD TAP..1
(-275 3100);
FORCEPROP 3 LASTPIN (-325 3100) SIG_NAME P3E_CPU0_PE2_SS_RXN<0>
J 0
(-315 3110);
DISPLAY 0.659574 (-315 3110);
PAINT MONO (-315 3110);
DISPLAY INVISIBLE (-315 3110);
FORCEPROP 1 LASTPIN (-325 3100) BN 0
J 0
(-337 3108);
DISPLAY 0.617021 (-337 3108);
PAINT GREEN (-337 3108);
FORCEPROP 2 LAST CDS_LIB mstr_standard
J 0
(-275 3100);
PAINT MONO (-275 3100);
DISPLAY INVISIBLE (-275 3100);
FORCEPROP 1 LAST PATH I36
J 0
(-277 3100);
DISPLAY 0.872340 (-277 3100);
PAINT GREEN (-277 3100);
DISPLAY INVISIBLE (-277 3100);
FORCEPROP 1 LAST BODY_TYPE PLUMBING
J 0
(-100 3150);
DISPLAY 0.872340 (-100 3150);
PAINT GREEN (-100 3150);
DISPLAY INVISIBLE (-100 3150);
FORCEPROP 1 LAST HDL_TAP TRUE
J 0
(225 2975);
DISPLAY 0.872340 (225 2975);
PAINT ORANGE (225 2975);
DISPLAY INVISIBLE (225 2975);
FORCEADD TAP..1
(-275 3250);
FORCEPROP 3 LASTPIN (-325 3250) SIG_NAME P3E_CPU0_PE1_SS_R_RXN<0>
J 0
(-315 3260);
DISPLAY 0.659574 (-315 3260);
PAINT MONO (-315 3260);
DISPLAY INVISIBLE (-315 3260);
FORCEPROP 1 LASTPIN (-325 3250) BN 0
J 0
(-337 3258);
DISPLAY 0.617021 (-337 3258);
PAINT GREEN (-337 3258);
FORCEPROP 2 LAST CDS_LIB mstr_standard
J 0
(-275 3250);
PAINT MONO (-275 3250);
DISPLAY INVISIBLE (-275 3250);
FORCEPROP 1 LAST PATH I37
J 0
(-277 3250);
DISPLAY 0.872340 (-277 3250);
PAINT GREEN (-277 3250);
DISPLAY INVISIBLE (-277 3250);
FORCEPROP 1 LAST BODY_TYPE PLUMBING
J 0
(-100 3300);
DISPLAY 0.872340 (-100 3300);
PAINT GREEN (-100 3300);
DISPLAY INVISIBLE (-100 3300);
FORCEPROP 1 LAST HDL_TAP TRUE
J 0
(225 3125);
DISPLAY 0.872340 (225 3125);
PAINT ORANGE (225 3125);
DISPLAY INVISIBLE (225 3125);
FORCEADD TAP..1
(-275 3400);
FORCEPROP 3 LASTPIN (-325 3400) SIG_NAME P3E_CPU0_PE1_SS_R_RXN<1>
J 0
(-315 3410);
DISPLAY 0.659574 (-315 3410);
PAINT MONO (-315 3410);
DISPLAY INVISIBLE (-315 3410);
FORCEPROP 1 LASTPIN (-325 3400) BN 1
J 0
(-337 3408);
DISPLAY 0.617021 (-337 3408);
PAINT GREEN (-337 3408);
FORCEPROP 2 LAST CDS_LIB mstr_standard
J 0
(-275 3400);
PAINT MONO (-275 3400);
DISPLAY INVISIBLE (-275 3400);
FORCEPROP 1 LAST PATH I38
J 0
(-277 3400);
DISPLAY 0.872340 (-277 3400);
PAINT GREEN (-277 3400);
DISPLAY INVISIBLE (-277 3400);
FORCEPROP 1 LAST BODY_TYPE PLUMBING
J 0
(-100 3450);
DISPLAY 0.872340 (-100 3450);
PAINT GREEN (-100 3450);
DISPLAY INVISIBLE (-100 3450);
FORCEPROP 1 LAST HDL_TAP TRUE
J 0
(225 3275);
DISPLAY 0.872340 (225 3275);
PAINT ORANGE (225 3275);
DISPLAY INVISIBLE (225 3275);
FORCEADD TAP..1
(-50 2450);
FORCEPROP 3 LASTPIN (-100 2450) SIG_NAME P3E_CPU0_PE2_SS_RXP<4>
J 0
(-90 2460);
DISPLAY 0.659574 (-90 2460);
PAINT MONO (-90 2460);
DISPLAY INVISIBLE (-90 2460);
FORCEPROP 1 LASTPIN (-100 2450) BN 4
J 0
(-112 2458);
DISPLAY 0.617021 (-112 2458);
PAINT GREEN (-112 2458);
FORCEPROP 2 LAST CDS_LIB mstr_standard
J 0
(-50 2450);
PAINT MONO (-50 2450);
DISPLAY INVISIBLE (-50 2450);
FORCEPROP 1 LAST PATH I39
J 0
(-52 2450);
DISPLAY 0.872340 (-52 2450);
PAINT GREEN (-52 2450);
DISPLAY INVISIBLE (-52 2450);
FORCEPROP 1 LAST BODY_TYPE PLUMBING
J 0
(125 2500);
DISPLAY 0.872340 (125 2500);
PAINT GREEN (125 2500);
DISPLAY INVISIBLE (125 2500);
FORCEPROP 1 LAST HDL_TAP TRUE
J 0
(450 2325);
DISPLAY 0.872340 (450 2325);
PAINT ORANGE (450 2325);
DISPLAY INVISIBLE (450 2325);
FORCEADD OFFPAGE..1
(-3500 4400);
FORCEPROP 2 LAST $XR0 107 
J 0
(-3752 4400);
DISPLAY 0.638298 (-3752 4400);
PAINT MONO (-3752 4400);
FORCEPROP 2 LAST PATH I4
J 0
(-3750 4450);
DISPLAY 1.021277 (-3750 4450);
PAINT ORANGE (-3750 4450);
DISPLAY INVISIBLE (-3750 4450);
FORCEPROP 2 LAST CDS_LIB mstr_standard
J 2
(-3500 4400);
PAINT MONO (-3500 4400);
DISPLAY INVISIBLE (-3500 4400);
FORCEPROP 1 LAST OFFPAGE TRUE
J 0
(-3175 4275);
DISPLAY 0.872340 (-3175 4275);
PAINT GREEN (-3175 4275);
DISPLAY INVISIBLE (-3175 4275);
FORCEPROP 1 LAST COMMENT_BODY TRUE
J 0
(-3375 4300);
DISPLAY 0.872340 (-3375 4300);
PAINT GREEN (-3375 4300);
DISPLAY INVISIBLE (-3375 4300);
FORCEADD TAP..1
(-50 2900);
FORCEPROP 3 LASTPIN (-100 2900) SIG_NAME P3E_CPU0_PE2_SS_RXP<1>
J 0
(-90 2910);
DISPLAY 0.659574 (-90 2910);
PAINT MONO (-90 2910);
DISPLAY INVISIBLE (-90 2910);
FORCEPROP 1 LASTPIN (-100 2900) BN 1
J 0
(-112 2908);
DISPLAY 0.617021 (-112 2908);
PAINT GREEN (-112 2908);
FORCEPROP 2 LAST CDS_LIB mstr_standard
J 0
(-50 2900);
PAINT MONO (-50 2900);
DISPLAY INVISIBLE (-50 2900);
FORCEPROP 1 LAST PATH I41
J 0
(-52 2900);
DISPLAY 0.872340 (-52 2900);
PAINT GREEN (-52 2900);
DISPLAY INVISIBLE (-52 2900);
FORCEPROP 1 LAST BODY_TYPE PLUMBING
J 0
(125 2950);
DISPLAY 0.872340 (125 2950);
PAINT GREEN (125 2950);
DISPLAY INVISIBLE (125 2950);
FORCEPROP 1 LAST HDL_TAP TRUE
J 0
(450 2775);
DISPLAY 0.872340 (450 2775);
PAINT ORANGE (450 2775);
DISPLAY INVISIBLE (450 2775);
FORCEADD TAP..1
(-50 3050);
FORCEPROP 3 LASTPIN (-100 3050) SIG_NAME P3E_CPU0_PE2_SS_RXP<0>
J 0
(-90 3060);
DISPLAY 0.659574 (-90 3060);
PAINT MONO (-90 3060);
DISPLAY INVISIBLE (-90 3060);
FORCEPROP 1 LASTPIN (-100 3050) BN 0
J 0
(-112 3058);
DISPLAY 0.617021 (-112 3058);
PAINT GREEN (-112 3058);
FORCEPROP 2 LAST CDS_LIB mstr_standard
J 0
(-50 3050);
PAINT MONO (-50 3050);
DISPLAY INVISIBLE (-50 3050);
FORCEPROP 1 LAST PATH I42
J 0
(-52 3050);
DISPLAY 0.872340 (-52 3050);
PAINT GREEN (-52 3050);
DISPLAY INVISIBLE (-52 3050);
FORCEPROP 1 LAST BODY_TYPE PLUMBING
J 0
(125 3100);
DISPLAY 0.872340 (125 3100);
PAINT GREEN (125 3100);
DISPLAY INVISIBLE (125 3100);
FORCEPROP 1 LAST HDL_TAP TRUE
J 0
(450 2925);
DISPLAY 0.872340 (450 2925);
PAINT ORANGE (450 2925);
DISPLAY INVISIBLE (450 2925);
FORCEADD TAP..1
(-50 3350);
FORCEPROP 3 LASTPIN (-100 3350) SIG_NAME P3E_CPU0_PE1_SS_R_RXP<1>
J 0
(-90 3360);
DISPLAY 0.659574 (-90 3360);
PAINT MONO (-90 3360);
DISPLAY INVISIBLE (-90 3360);
FORCEPROP 1 LASTPIN (-100 3350) BN 1
J 0
(-112 3358);
DISPLAY 0.617021 (-112 3358);
PAINT GREEN (-112 3358);
FORCEPROP 2 LAST CDS_LIB mstr_standard
J 0
(-50 3350);
PAINT MONO (-50 3350);
DISPLAY INVISIBLE (-50 3350);
FORCEPROP 1 LAST PATH I43
J 0
(-52 3350);
DISPLAY 0.872340 (-52 3350);
PAINT GREEN (-52 3350);
DISPLAY INVISIBLE (-52 3350);
FORCEPROP 1 LAST BODY_TYPE PLUMBING
J 0
(125 3400);
DISPLAY 0.872340 (125 3400);
PAINT GREEN (125 3400);
DISPLAY INVISIBLE (125 3400);
FORCEPROP 1 LAST HDL_TAP TRUE
J 0
(450 3225);
DISPLAY 0.872340 (450 3225);
PAINT ORANGE (450 3225);
DISPLAY INVISIBLE (450 3225);
FORCEADD TAP..1
(-50 3200);
FORCEPROP 3 LASTPIN (-100 3200) SIG_NAME P3E_CPU0_PE1_SS_R_RXP<0>
J 0
(-90 3210);
DISPLAY 0.659574 (-90 3210);
PAINT MONO (-90 3210);
DISPLAY INVISIBLE (-90 3210);
FORCEPROP 1 LASTPIN (-100 3200) BN 0
J 0
(-112 3208);
DISPLAY 0.617021 (-112 3208);
PAINT GREEN (-112 3208);
FORCEPROP 2 LAST CDS_LIB mstr_standard
J 0
(-50 3200);
PAINT MONO (-50 3200);
DISPLAY INVISIBLE (-50 3200);
FORCEPROP 1 LAST PATH I44
J 0
(-52 3200);
DISPLAY 0.872340 (-52 3200);
PAINT GREEN (-52 3200);
DISPLAY INVISIBLE (-52 3200);
FORCEPROP 1 LAST BODY_TYPE PLUMBING
J 0
(125 3250);
DISPLAY 0.872340 (125 3250);
PAINT GREEN (125 3250);
DISPLAY INVISIBLE (125 3250);
FORCEPROP 1 LAST HDL_TAP TRUE
J 0
(450 3075);
DISPLAY 0.872340 (450 3075);
PAINT ORANGE (450 3075);
DISPLAY INVISIBLE (450 3075);
FORCEADD OFFPAGE..2
(1200 3100);
FORCEPROP 2 LAST $XR0 31 
J 0
(1389 3100);
DISPLAY 0.638298 (1389 3100);
PAINT MONO (1389 3100);
FORCEPROP 2 LAST CDS_LIB mstr_standard
J 0
(1200 3100);
PAINT MONO (1200 3100);
DISPLAY INVISIBLE (1200 3100);
FORCEPROP 2 LAST PATH I45
J 0
(1400 3150);
DISPLAY 1.021277 (1400 3150);
PAINT ORANGE (1400 3150);
DISPLAY INVISIBLE (1400 3150);
FORCEPROP 1 LAST OFFPAGE TRUE
J 0
(1525 2975);
DISPLAY 0.872340 (1525 2975);
PAINT GREEN (1525 2975);
DISPLAY INVISIBLE (1525 2975);
FORCEPROP 1 LAST COMMENT_BODY TRUE
J 0
(1155 3005);
DISPLAY 0.872340 (1155 3005);
PAINT GREEN (1155 3005);
DISPLAY INVISIBLE (1155 3005);
FORCEADD OFFPAGE..2
(1200 3150);
FORCEPROP 2 LAST $XR0 31 
J 0
(1389 3150);
DISPLAY 0.638298 (1389 3150);
PAINT MONO (1389 3150);
FORCEPROP 2 LAST PATH I46
J 0
(1400 3200);
DISPLAY 1.021277 (1400 3200);
PAINT ORANGE (1400 3200);
DISPLAY INVISIBLE (1400 3200);
FORCEPROP 2 LAST CDS_LIB mstr_standard
J 0
(1200 3150);
PAINT MONO (1200 3150);
DISPLAY INVISIBLE (1200 3150);
FORCEPROP 1 LAST OFFPAGE TRUE
J 0
(1525 3025);
DISPLAY 0.872340 (1525 3025);
PAINT GREEN (1525 3025);
DISPLAY INVISIBLE (1525 3025);
FORCEPROP 1 LAST COMMENT_BODY TRUE
J 0
(1155 3055);
DISPLAY 0.872340 (1155 3055);
PAINT GREEN (1155 3055);
DISPLAY INVISIBLE (1155 3055);
FORCEADD TAP..1
R 2
(-2300 3550);
FORCEPROP 3 LASTPIN (-2250 3550) SIG_NAME P3E_CPU0_PE1_SS_C_TXP<2>
J 0
(-2240 3560);
DISPLAY 0.659574 (-2240 3560);
PAINT MONO (-2240 3560);
DISPLAY INVISIBLE (-2240 3560);
FORCEPROP 1 LASTPIN (-2250 3550) BN 2
J 2
(-2238 3558);
DISPLAY 0.617021 (-2238 3558);
PAINT GREEN (-2238 3558);
FORCEPROP 2 LAST CDS_LIB mstr_standard
J 0
(-2300 3550);
PAINT MONO (-2300 3550);
DISPLAY INVISIBLE (-2300 3550);
FORCEPROP 1 LAST PATH I48
J 2
(-2298 3550);
DISPLAY 0.872340 (-2298 3550);
PAINT GREEN (-2298 3550);
DISPLAY INVISIBLE (-2298 3550);
FORCEPROP 1 LAST BODY_TYPE PLUMBING
J 2
(-2300 3600);
DISPLAY 0.872340 (-2300 3600);
PAINT GREEN (-2300 3600);
DISPLAY INVISIBLE (-2300 3600);
FORCEPROP 1 LAST HDL_TAP TRUE
J 2
(-2625 3425);
DISPLAY 0.872340 (-2625 3425);
PAINT ORANGE (-2625 3425);
DISPLAY INVISIBLE (-2625 3425);
FORCEADD OFFPAGE..1
(-3500 4450);
FORCEPROP 2 LAST $XR0 107 
J 0
(-3752 4450);
DISPLAY 0.638298 (-3752 4450);
PAINT MONO (-3752 4450);
FORCEPROP 2 LAST PATH I5
J 0
(-3750 4500);
DISPLAY 1.021277 (-3750 4500);
PAINT ORANGE (-3750 4500);
DISPLAY INVISIBLE (-3750 4500);
FORCEPROP 2 LAST CDS_LIB mstr_standard
J 0
(-3500 4450);
PAINT MONO (-3500 4450);
DISPLAY INVISIBLE (-3500 4450);
FORCEPROP 1 LAST OFFPAGE TRUE
J 0
(-3175 4325);
DISPLAY 0.872340 (-3175 4325);
PAINT GREEN (-3175 4325);
DISPLAY INVISIBLE (-3175 4325);
FORCEPROP 1 LAST COMMENT_BODY TRUE
J 0
(-3375 4350);
DISPLAY 0.872340 (-3375 4350);
PAINT GREEN (-3375 4350);
DISPLAY INVISIBLE (-3375 4350);
FORCEADD TAP..1
R 2
(-2300 3700);
FORCEPROP 3 LASTPIN (-2250 3700) SIG_NAME P3E_CPU0_PE1_SS_C_TXP<3>
J 0
(-2240 3710);
DISPLAY 0.659574 (-2240 3710);
PAINT MONO (-2240 3710);
DISPLAY INVISIBLE (-2240 3710);
FORCEPROP 1 LASTPIN (-2250 3700) BN 3
J 2
(-2238 3708);
DISPLAY 0.617021 (-2238 3708);
PAINT GREEN (-2238 3708);
FORCEPROP 2 LAST CDS_LIB mstr_standard
J 0
(-2300 3700);
PAINT MONO (-2300 3700);
DISPLAY INVISIBLE (-2300 3700);
FORCEPROP 1 LAST PATH I50
J 2
(-2298 3700);
DISPLAY 0.872340 (-2298 3700);
PAINT GREEN (-2298 3700);
DISPLAY INVISIBLE (-2298 3700);
FORCEPROP 1 LAST BODY_TYPE PLUMBING
J 2
(-2300 3750);
DISPLAY 0.872340 (-2300 3750);
PAINT GREEN (-2300 3750);
DISPLAY INVISIBLE (-2300 3750);
FORCEPROP 1 LAST HDL_TAP TRUE
J 2
(-2625 3575);
DISPLAY 0.872340 (-2625 3575);
PAINT ORANGE (-2625 3575);
DISPLAY INVISIBLE (-2625 3575);
FORCEADD TAP..1
R 2
(-2300 4000);
FORCEPROP 3 LASTPIN (-2250 4000) SIG_NAME P3E_CPU0_PE1_SS_C_TXP<5>
J 0
(-2240 4010);
DISPLAY 0.659574 (-2240 4010);
PAINT MONO (-2240 4010);
DISPLAY INVISIBLE (-2240 4010);
FORCEPROP 1 LASTPIN (-2250 4000) BN 5
J 2
(-2238 4008);
DISPLAY 0.617021 (-2238 4008);
PAINT GREEN (-2238 4008);
FORCEPROP 2 LAST CDS_LIB mstr_standard
J 0
(-2300 4000);
PAINT MONO (-2300 4000);
DISPLAY INVISIBLE (-2300 4000);
FORCEPROP 1 LAST PATH I51
J 2
(-2298 4000);
DISPLAY 0.872340 (-2298 4000);
PAINT GREEN (-2298 4000);
DISPLAY INVISIBLE (-2298 4000);
FORCEPROP 1 LAST BODY_TYPE PLUMBING
J 2
(-2300 4050);
DISPLAY 0.872340 (-2300 4050);
PAINT GREEN (-2300 4050);
DISPLAY INVISIBLE (-2300 4050);
FORCEPROP 1 LAST HDL_TAP TRUE
J 2
(-2625 3875);
DISPLAY 0.872340 (-2625 3875);
PAINT ORANGE (-2625 3875);
DISPLAY INVISIBLE (-2625 3875);
FORCEADD TAP..1
R 2
(-2300 4150);
FORCEPROP 3 LASTPIN (-2250 4150) SIG_NAME P3E_CPU0_PE1_SS_C_TXP<6>
J 0
(-2240 4160);
DISPLAY 0.659574 (-2240 4160);
PAINT MONO (-2240 4160);
DISPLAY INVISIBLE (-2240 4160);
FORCEPROP 1 LASTPIN (-2250 4150) BN 6
J 2
(-2238 4158);
DISPLAY 0.617021 (-2238 4158);
PAINT GREEN (-2238 4158);
FORCEPROP 2 LAST CDS_LIB mstr_standard
J 0
(-2300 4150);
PAINT MONO (-2300 4150);
DISPLAY INVISIBLE (-2300 4150);
FORCEPROP 1 LAST PATH I52
J 2
(-2298 4150);
DISPLAY 0.872340 (-2298 4150);
PAINT GREEN (-2298 4150);
DISPLAY INVISIBLE (-2298 4150);
FORCEPROP 1 LAST BODY_TYPE PLUMBING
J 2
(-2300 4200);
DISPLAY 0.872340 (-2300 4200);
PAINT GREEN (-2300 4200);
DISPLAY INVISIBLE (-2300 4200);
FORCEPROP 1 LAST HDL_TAP TRUE
J 2
(-2625 4025);
DISPLAY 0.872340 (-2625 4025);
PAINT ORANGE (-2625 4025);
DISPLAY INVISIBLE (-2625 4025);
FORCEADD TAP..1
R 2
(-2050 3600);
FORCEPROP 3 LASTPIN (-2000 3600) SIG_NAME P3E_CPU0_PE1_SS_C_TXN<2>
J 0
(-1990 3610);
DISPLAY 0.659574 (-1990 3610);
PAINT MONO (-1990 3610);
DISPLAY INVISIBLE (-1990 3610);
FORCEPROP 1 LASTPIN (-2000 3600) BN 2
J 2
(-1988 3608);
DISPLAY 0.617021 (-1988 3608);
PAINT GREEN (-1988 3608);
FORCEPROP 2 LAST CDS_LIB mstr_standard
J 0
(-2050 3600);
PAINT MONO (-2050 3600);
DISPLAY INVISIBLE (-2050 3600);
FORCEPROP 1 LAST PATH I54
J 2
(-2048 3600);
DISPLAY 0.872340 (-2048 3600);
PAINT GREEN (-2048 3600);
DISPLAY INVISIBLE (-2048 3600);
FORCEPROP 1 LAST BODY_TYPE PLUMBING
J 2
(-2050 3650);
DISPLAY 0.872340 (-2050 3650);
PAINT GREEN (-2050 3650);
DISPLAY INVISIBLE (-2050 3650);
FORCEPROP 1 LAST HDL_TAP TRUE
J 2
(-2375 3475);
DISPLAY 0.872340 (-2375 3475);
PAINT ORANGE (-2375 3475);
DISPLAY INVISIBLE (-2375 3475);
FORCEADD TAP..1
R 2
(-2050 3750);
FORCEPROP 3 LASTPIN (-2000 3750) SIG_NAME P3E_CPU0_PE1_SS_C_TXN<3>
J 0
(-1990 3760);
DISPLAY 0.659574 (-1990 3760);
PAINT MONO (-1990 3760);
DISPLAY INVISIBLE (-1990 3760);
FORCEPROP 1 LASTPIN (-2000 3750) BN 3
J 2
(-1988 3758);
DISPLAY 0.617021 (-1988 3758);
PAINT GREEN (-1988 3758);
FORCEPROP 2 LAST CDS_LIB mstr_standard
J 0
(-2050 3750);
PAINT MONO (-2050 3750);
DISPLAY INVISIBLE (-2050 3750);
FORCEPROP 1 LAST PATH I55
J 2
(-2048 3750);
DISPLAY 0.872340 (-2048 3750);
PAINT GREEN (-2048 3750);
DISPLAY INVISIBLE (-2048 3750);
FORCEPROP 1 LAST BODY_TYPE PLUMBING
J 2
(-2050 3800);
DISPLAY 0.872340 (-2050 3800);
PAINT GREEN (-2050 3800);
DISPLAY INVISIBLE (-2050 3800);
FORCEPROP 1 LAST HDL_TAP TRUE
J 2
(-2375 3625);
DISPLAY 0.872340 (-2375 3625);
PAINT ORANGE (-2375 3625);
DISPLAY INVISIBLE (-2375 3625);
FORCEADD TAP..1
R 2
(-2050 4050);
FORCEPROP 3 LASTPIN (-2000 4050) SIG_NAME P3E_CPU0_PE1_SS_C_TXN<5>
J 0
(-1990 4060);
DISPLAY 0.659574 (-1990 4060);
PAINT MONO (-1990 4060);
DISPLAY INVISIBLE (-1990 4060);
FORCEPROP 1 LASTPIN (-2000 4050) BN 5
J 2
(-1988 4058);
DISPLAY 0.617021 (-1988 4058);
PAINT GREEN (-1988 4058);
FORCEPROP 2 LAST CDS_LIB mstr_standard
J 0
(-2050 4050);
PAINT MONO (-2050 4050);
DISPLAY INVISIBLE (-2050 4050);
FORCEPROP 1 LAST PATH I57
J 2
(-2048 4050);
DISPLAY 0.872340 (-2048 4050);
PAINT GREEN (-2048 4050);
DISPLAY INVISIBLE (-2048 4050);
FORCEPROP 1 LAST BODY_TYPE PLUMBING
J 2
(-2050 4100);
DISPLAY 0.872340 (-2050 4100);
PAINT GREEN (-2050 4100);
DISPLAY INVISIBLE (-2050 4100);
FORCEPROP 1 LAST HDL_TAP TRUE
J 2
(-2375 3925);
DISPLAY 0.872340 (-2375 3925);
PAINT ORANGE (-2375 3925);
DISPLAY INVISIBLE (-2375 3925);
FORCEADD TAP..1
R 2
(-2050 4200);
FORCEPROP 3 LASTPIN (-2000 4200) SIG_NAME P3E_CPU0_PE1_SS_C_TXN<6>
J 0
(-1990 4210);
DISPLAY 0.659574 (-1990 4210);
PAINT MONO (-1990 4210);
DISPLAY INVISIBLE (-1990 4210);
FORCEPROP 1 LASTPIN (-2000 4200) BN 6
J 2
(-1988 4208);
DISPLAY 0.617021 (-1988 4208);
PAINT GREEN (-1988 4208);
FORCEPROP 2 LAST CDS_LIB mstr_standard
J 0
(-2050 4200);
PAINT MONO (-2050 4200);
DISPLAY INVISIBLE (-2050 4200);
FORCEPROP 1 LAST PATH I58
J 2
(-2048 4200);
DISPLAY 0.872340 (-2048 4200);
PAINT GREEN (-2048 4200);
DISPLAY INVISIBLE (-2048 4200);
FORCEPROP 1 LAST BODY_TYPE PLUMBING
J 2
(-2050 4250);
DISPLAY 0.872340 (-2050 4250);
PAINT GREEN (-2050 4250);
DISPLAY INVISIBLE (-2050 4250);
FORCEPROP 1 LAST HDL_TAP TRUE
J 2
(-2375 4075);
DISPLAY 0.872340 (-2375 4075);
PAINT ORANGE (-2375 4075);
DISPLAY INVISIBLE (-2375 4075);
FORCEADD TAP..1
R 2
(-2300 2100);
FORCEPROP 3 LASTPIN (-2250 2100) SIG_NAME P3E_CPU0_PE2_SS_C_TXN<7>
J 0
(-2240 2110);
DISPLAY 0.659574 (-2240 2110);
PAINT MONO (-2240 2110);
DISPLAY INVISIBLE (-2240 2110);
FORCEPROP 1 LASTPIN (-2250 2100) BN 7
J 2
(-2238 2108);
DISPLAY 0.617021 (-2238 2108);
PAINT GREEN (-2238 2108);
FORCEPROP 2 LAST CDS_LIB mstr_standard
J 0
(-2300 2100);
PAINT MONO (-2300 2100);
DISPLAY INVISIBLE (-2300 2100);
FORCEPROP 1 LAST PATH I6
J 2
(-2298 2100);
DISPLAY 0.872340 (-2298 2100);
PAINT GREEN (-2298 2100);
DISPLAY INVISIBLE (-2298 2100);
FORCEPROP 1 LAST BODY_TYPE PLUMBING
J 2
(-2300 2150);
DISPLAY 0.872340 (-2300 2150);
PAINT GREEN (-2300 2150);
DISPLAY INVISIBLE (-2300 2150);
FORCEPROP 1 LAST HDL_TAP TRUE
J 2
(-2625 1975);
DISPLAY 0.872340 (-2625 1975);
PAINT ORANGE (-2625 1975);
DISPLAY INVISIBLE (-2625 1975);
FORCEADD TAP..1
(-275 3700);
FORCEPROP 3 LASTPIN (-325 3700) SIG_NAME P3E_CPU0_PE1_SS_R_RXN<3>
J 0
(-315 3710);
DISPLAY 0.659574 (-315 3710);
PAINT MONO (-315 3710);
DISPLAY INVISIBLE (-315 3710);
FORCEPROP 1 LASTPIN (-325 3700) BN 3
J 0
(-337 3708);
DISPLAY 0.617021 (-337 3708);
PAINT GREEN (-337 3708);
FORCEPROP 2 LAST CDS_LIB mstr_standard
J 0
(-275 3700);
PAINT MONO (-275 3700);
DISPLAY INVISIBLE (-275 3700);
FORCEPROP 1 LAST PATH I61
J 0
(-277 3700);
DISPLAY 0.872340 (-277 3700);
PAINT GREEN (-277 3700);
DISPLAY INVISIBLE (-277 3700);
FORCEPROP 1 LAST BODY_TYPE PLUMBING
J 0
(-100 3750);
DISPLAY 0.872340 (-100 3750);
PAINT GREEN (-100 3750);
DISPLAY INVISIBLE (-100 3750);
FORCEPROP 1 LAST HDL_TAP TRUE
J 0
(225 3575);
DISPLAY 0.872340 (225 3575);
PAINT ORANGE (225 3575);
DISPLAY INVISIBLE (225 3575);
FORCEADD TAP..1
(-275 3850);
FORCEPROP 3 LASTPIN (-325 3850) SIG_NAME P3E_CPU0_PE1_SS_R_RXN<4>
J 0
(-315 3860);
DISPLAY 0.659574 (-315 3860);
PAINT MONO (-315 3860);
DISPLAY INVISIBLE (-315 3860);
FORCEPROP 1 LASTPIN (-325 3850) BN 4
J 0
(-337 3858);
DISPLAY 0.617021 (-337 3858);
PAINT GREEN (-337 3858);
FORCEPROP 2 LAST CDS_LIB mstr_standard
J 0
(-275 3850);
PAINT MONO (-275 3850);
DISPLAY INVISIBLE (-275 3850);
FORCEPROP 1 LAST PATH I62
J 0
(-277 3850);
DISPLAY 0.872340 (-277 3850);
PAINT GREEN (-277 3850);
DISPLAY INVISIBLE (-277 3850);
FORCEPROP 1 LAST BODY_TYPE PLUMBING
J 0
(-100 3900);
DISPLAY 0.872340 (-100 3900);
PAINT GREEN (-100 3900);
DISPLAY INVISIBLE (-100 3900);
FORCEPROP 1 LAST HDL_TAP TRUE
J 0
(225 3725);
DISPLAY 0.872340 (225 3725);
PAINT ORANGE (225 3725);
DISPLAY INVISIBLE (225 3725);
FORCEADD TAP..1
(-275 4000);
FORCEPROP 3 LASTPIN (-325 4000) SIG_NAME P3E_CPU0_PE1_SS_R_RXN<5>
J 0
(-315 4010);
DISPLAY 0.659574 (-315 4010);
PAINT MONO (-315 4010);
DISPLAY INVISIBLE (-315 4010);
FORCEPROP 1 LASTPIN (-325 4000) BN 5
J 0
(-337 4008);
DISPLAY 0.617021 (-337 4008);
PAINT GREEN (-337 4008);
FORCEPROP 2 LAST CDS_LIB mstr_standard
J 0
(-275 4000);
PAINT MONO (-275 4000);
DISPLAY INVISIBLE (-275 4000);
FORCEPROP 1 LAST PATH I63
J 0
(-277 4000);
DISPLAY 0.872340 (-277 4000);
PAINT GREEN (-277 4000);
DISPLAY INVISIBLE (-277 4000);
FORCEPROP 1 LAST BODY_TYPE PLUMBING
J 0
(-100 4050);
DISPLAY 0.872340 (-100 4050);
PAINT GREEN (-100 4050);
DISPLAY INVISIBLE (-100 4050);
FORCEPROP 1 LAST HDL_TAP TRUE
J 0
(225 3875);
DISPLAY 0.872340 (225 3875);
PAINT ORANGE (225 3875);
DISPLAY INVISIBLE (225 3875);
FORCEADD TAP..1
(-275 4150);
FORCEPROP 3 LASTPIN (-325 4150) SIG_NAME P3E_CPU0_PE1_SS_R_RXN<6>
J 0
(-315 4160);
DISPLAY 0.659574 (-315 4160);
PAINT MONO (-315 4160);
DISPLAY INVISIBLE (-315 4160);
FORCEPROP 1 LASTPIN (-325 4150) BN 6
J 0
(-337 4158);
DISPLAY 0.617021 (-337 4158);
PAINT GREEN (-337 4158);
FORCEPROP 2 LAST CDS_LIB mstr_standard
J 0
(-275 4150);
PAINT MONO (-275 4150);
DISPLAY INVISIBLE (-275 4150);
FORCEPROP 1 LAST PATH I64
J 0
(-277 4150);
DISPLAY 0.872340 (-277 4150);
PAINT GREEN (-277 4150);
DISPLAY INVISIBLE (-277 4150);
FORCEPROP 1 LAST BODY_TYPE PLUMBING
J 0
(-100 4200);
DISPLAY 0.872340 (-100 4200);
PAINT GREEN (-100 4200);
DISPLAY INVISIBLE (-100 4200);
FORCEPROP 1 LAST HDL_TAP TRUE
J 0
(225 4025);
DISPLAY 0.872340 (225 4025);
PAINT ORANGE (225 4025);
DISPLAY INVISIBLE (225 4025);
FORCEADD TAP..1
(-275 4300);
FORCEPROP 3 LASTPIN (-325 4300) SIG_NAME P3E_CPU0_PE1_SS_R_RXN<7>
J 0
(-315 4310);
DISPLAY 0.659574 (-315 4310);
PAINT MONO (-315 4310);
DISPLAY INVISIBLE (-315 4310);
FORCEPROP 1 LASTPIN (-325 4300) BN 7
J 0
(-337 4308);
DISPLAY 0.617021 (-337 4308);
PAINT GREEN (-337 4308);
FORCEPROP 2 LAST CDS_LIB mstr_standard
J 0
(-275 4300);
PAINT MONO (-275 4300);
DISPLAY INVISIBLE (-275 4300);
FORCEPROP 1 LAST PATH I65
J 0
(-277 4300);
DISPLAY 0.872340 (-277 4300);
PAINT GREEN (-277 4300);
DISPLAY INVISIBLE (-277 4300);
FORCEPROP 1 LAST BODY_TYPE PLUMBING
J 0
(-100 4350);
DISPLAY 0.872340 (-100 4350);
PAINT GREEN (-100 4350);
DISPLAY INVISIBLE (-100 4350);
FORCEPROP 1 LAST HDL_TAP TRUE
J 0
(225 4175);
DISPLAY 0.872340 (225 4175);
PAINT ORANGE (225 4175);
DISPLAY INVISIBLE (225 4175);
FORCEADD TAP..1
(-275 4400);
FORCEPROP 3 LASTPIN (-325 4400) SIG_NAME P3E_CPU0_PE1_PCH_CON_RXP<8>
J 0
(-315 4410);
DISPLAY 0.659574 (-315 4410);
PAINT MONO (-315 4410);
DISPLAY INVISIBLE (-315 4410);
FORCEPROP 1 LASTPIN (-325 4400) BN 8
J 0
(-337 4408);
DISPLAY 0.617021 (-337 4408);
PAINT GREEN (-337 4408);
FORCEPROP 2 LAST CDS_LIB mstr_standard
J 0
(-275 4400);
PAINT ORANGE (-275 4400);
DISPLAY INVISIBLE (-275 4400);
FORCEPROP 1 LAST PATH I66
J 0
(-277 4400);
DISPLAY 0.872340 (-277 4400);
PAINT GREEN (-277 4400);
DISPLAY INVISIBLE (-277 4400);
FORCEPROP 1 LAST BODY_TYPE PLUMBING
J 0
(-100 4450);
DISPLAY 0.872340 (-100 4450);
PAINT GREEN (-100 4450);
DISPLAY INVISIBLE (-100 4450);
FORCEPROP 1 LAST HDL_TAP TRUE
J 0
(225 4275);
DISPLAY 0.872340 (225 4275);
PAINT ORANGE (225 4275);
DISPLAY INVISIBLE (225 4275);
FORCEADD TAP..1
(-50 3650);
FORCEPROP 3 LASTPIN (-100 3650) SIG_NAME P3E_CPU0_PE1_SS_R_RXP<3>
J 0
(-90 3660);
DISPLAY 0.659574 (-90 3660);
PAINT MONO (-90 3660);
DISPLAY INVISIBLE (-90 3660);
FORCEPROP 1 LASTPIN (-100 3650) BN 3
J 0
(-112 3658);
DISPLAY 0.617021 (-112 3658);
PAINT GREEN (-112 3658);
FORCEPROP 2 LAST CDS_LIB mstr_standard
J 0
(-50 3650);
PAINT MONO (-50 3650);
DISPLAY INVISIBLE (-50 3650);
FORCEPROP 1 LAST PATH I67
J 0
(-52 3650);
DISPLAY 0.872340 (-52 3650);
PAINT GREEN (-52 3650);
DISPLAY INVISIBLE (-52 3650);
FORCEPROP 1 LAST BODY_TYPE PLUMBING
J 0
(125 3700);
DISPLAY 0.872340 (125 3700);
PAINT GREEN (125 3700);
DISPLAY INVISIBLE (125 3700);
FORCEPROP 1 LAST HDL_TAP TRUE
J 0
(450 3525);
DISPLAY 0.872340 (450 3525);
PAINT ORANGE (450 3525);
DISPLAY INVISIBLE (450 3525);
FORCEADD TAP..1
(-50 3800);
FORCEPROP 3 LASTPIN (-100 3800) SIG_NAME P3E_CPU0_PE1_SS_R_RXP<4>
J 0
(-90 3810);
DISPLAY 0.659574 (-90 3810);
PAINT MONO (-90 3810);
DISPLAY INVISIBLE (-90 3810);
FORCEPROP 1 LASTPIN (-100 3800) BN 4
J 0
(-112 3808);
DISPLAY 0.617021 (-112 3808);
PAINT GREEN (-112 3808);
FORCEPROP 2 LAST CDS_LIB mstr_standard
J 0
(-50 3800);
PAINT MONO (-50 3800);
DISPLAY INVISIBLE (-50 3800);
FORCEPROP 1 LAST PATH I69
J 0
(-52 3800);
DISPLAY 0.872340 (-52 3800);
PAINT GREEN (-52 3800);
DISPLAY INVISIBLE (-52 3800);
FORCEPROP 1 LAST BODY_TYPE PLUMBING
J 0
(125 3850);
DISPLAY 0.872340 (125 3850);
PAINT GREEN (125 3850);
DISPLAY INVISIBLE (125 3850);
FORCEPROP 1 LAST HDL_TAP TRUE
J 0
(450 3675);
DISPLAY 0.872340 (450 3675);
PAINT ORANGE (450 3675);
DISPLAY INVISIBLE (450 3675);
FORCEADD TAP..1
R 2
(-2300 2250);
FORCEPROP 3 LASTPIN (-2250 2250) SIG_NAME P3E_CPU0_PE2_SS_C_TXN<6>
J 0
(-2240 2260);
DISPLAY 0.659574 (-2240 2260);
PAINT MONO (-2240 2260);
DISPLAY INVISIBLE (-2240 2260);
FORCEPROP 1 LASTPIN (-2250 2250) BN 6
J 2
(-2238 2258);
DISPLAY 0.617021 (-2238 2258);
PAINT GREEN (-2238 2258);
FORCEPROP 2 LAST CDS_LIB mstr_standard
J 0
(-2300 2250);
PAINT MONO (-2300 2250);
DISPLAY INVISIBLE (-2300 2250);
FORCEPROP 1 LAST PATH I7
J 2
(-2298 2250);
DISPLAY 0.872340 (-2298 2250);
PAINT GREEN (-2298 2250);
DISPLAY INVISIBLE (-2298 2250);
FORCEPROP 1 LAST BODY_TYPE PLUMBING
J 2
(-2300 2300);
DISPLAY 0.872340 (-2300 2300);
PAINT GREEN (-2300 2300);
DISPLAY INVISIBLE (-2300 2300);
FORCEPROP 1 LAST HDL_TAP TRUE
J 2
(-2625 2125);
DISPLAY 0.872340 (-2625 2125);
PAINT ORANGE (-2625 2125);
DISPLAY INVISIBLE (-2625 2125);
FORCEADD TAP..1
(-50 3950);
FORCEPROP 3 LASTPIN (-100 3950) SIG_NAME P3E_CPU0_PE1_SS_R_RXP<5>
J 0
(-90 3960);
DISPLAY 0.659574 (-90 3960);
PAINT MONO (-90 3960);
DISPLAY INVISIBLE (-90 3960);
FORCEPROP 1 LASTPIN (-100 3950) BN 5
J 0
(-112 3958);
DISPLAY 0.617021 (-112 3958);
PAINT GREEN (-112 3958);
FORCEPROP 2 LAST CDS_LIB mstr_standard
J 0
(-50 3950);
PAINT MONO (-50 3950);
DISPLAY INVISIBLE (-50 3950);
FORCEPROP 1 LAST PATH I70
J 0
(-52 3950);
DISPLAY 0.872340 (-52 3950);
PAINT GREEN (-52 3950);
DISPLAY INVISIBLE (-52 3950);
FORCEPROP 1 LAST BODY_TYPE PLUMBING
J 0
(125 4000);
DISPLAY 0.872340 (125 4000);
PAINT GREEN (125 4000);
DISPLAY INVISIBLE (125 4000);
FORCEPROP 1 LAST HDL_TAP TRUE
J 0
(450 3825);
DISPLAY 0.872340 (450 3825);
PAINT ORANGE (450 3825);
DISPLAY INVISIBLE (450 3825);
FORCEADD TAP..1
(-50 4100);
FORCEPROP 3 LASTPIN (-100 4100) SIG_NAME P3E_CPU0_PE1_SS_R_RXP<6>
J 0
(-90 4110);
DISPLAY 0.659574 (-90 4110);
PAINT MONO (-90 4110);
DISPLAY INVISIBLE (-90 4110);
FORCEPROP 1 LASTPIN (-100 4100) BN 6
J 0
(-112 4108);
DISPLAY 0.617021 (-112 4108);
PAINT GREEN (-112 4108);
FORCEPROP 2 LAST CDS_LIB mstr_standard
J 0
(-50 4100);
PAINT MONO (-50 4100);
DISPLAY INVISIBLE (-50 4100);
FORCEPROP 1 LAST PATH I71
J 0
(-52 4100);
DISPLAY 0.872340 (-52 4100);
PAINT GREEN (-52 4100);
DISPLAY INVISIBLE (-52 4100);
FORCEPROP 1 LAST BODY_TYPE PLUMBING
J 0
(125 4150);
DISPLAY 0.872340 (125 4150);
PAINT GREEN (125 4150);
DISPLAY INVISIBLE (125 4150);
FORCEPROP 1 LAST HDL_TAP TRUE
J 0
(450 3975);
DISPLAY 0.872340 (450 3975);
PAINT ORANGE (450 3975);
DISPLAY INVISIBLE (450 3975);
FORCEADD TAP..1
(-50 4250);
FORCEPROP 3 LASTPIN (-100 4250) SIG_NAME P3E_CPU0_PE1_SS_R_RXP<7>
J 0
(-90 4260);
DISPLAY 0.659574 (-90 4260);
PAINT MONO (-90 4260);
DISPLAY INVISIBLE (-90 4260);
FORCEPROP 1 LASTPIN (-100 4250) BN 7
J 0
(-112 4258);
DISPLAY 0.617021 (-112 4258);
PAINT GREEN (-112 4258);
FORCEPROP 2 LAST CDS_LIB mstr_standard
J 0
(-50 4250);
PAINT MONO (-50 4250);
DISPLAY INVISIBLE (-50 4250);
FORCEPROP 1 LAST PATH I72
J 0
(-52 4250);
DISPLAY 0.872340 (-52 4250);
PAINT GREEN (-52 4250);
DISPLAY INVISIBLE (-52 4250);
FORCEPROP 1 LAST BODY_TYPE PLUMBING
J 0
(125 4300);
DISPLAY 0.872340 (125 4300);
PAINT GREEN (125 4300);
DISPLAY INVISIBLE (125 4300);
FORCEPROP 1 LAST HDL_TAP TRUE
J 0
(450 4125);
DISPLAY 0.872340 (450 4125);
PAINT ORANGE (450 4125);
DISPLAY INVISIBLE (450 4125);
FORCEADD OFFPAGE..2
(1200 4300);
FORCEPROP 2 LAST $XR0 107 
J 0
(1389 4300);
DISPLAY 0.638298 (1389 4300);
PAINT MONO (1389 4300);
FORCEPROP 2 LAST CDS_LIB mstr_standard
J 0
(1200 4300);
PAINT MONO (1200 4300);
DISPLAY INVISIBLE (1200 4300);
FORCEPROP 2 LAST PATH I73
J 0
(1525 4350);
DISPLAY 1.021277 (1525 4350);
PAINT ORANGE (1525 4350);
DISPLAY INVISIBLE (1525 4350);
FORCEPROP 1 LAST OFFPAGE TRUE
J 0
(1525 4175);
DISPLAY 0.872340 (1525 4175);
PAINT GREEN (1525 4175);
DISPLAY INVISIBLE (1525 4175);
FORCEPROP 1 LAST COMMENT_BODY TRUE
J 0
(1155 4205);
DISPLAY 0.872340 (1155 4205);
PAINT GREEN (1155 4205);
DISPLAY INVISIBLE (1155 4205);
FORCEADD OFFPAGE..2
(1200 4350);
FORCEPROP 2 LAST $XR0 107 
J 0
(1389 4350);
DISPLAY 0.638298 (1389 4350);
PAINT MONO (1389 4350);
FORCEPROP 2 LAST CDS_LIB mstr_standard
J 0
(1200 4350);
PAINT MONO (1200 4350);
DISPLAY INVISIBLE (1200 4350);
FORCEPROP 2 LAST PATH I74
J 0
(1525 4400);
DISPLAY 1.021277 (1525 4400);
PAINT ORANGE (1525 4400);
DISPLAY INVISIBLE (1525 4400);
FORCEPROP 1 LAST OFFPAGE TRUE
J 0
(1525 4225);
DISPLAY 0.872340 (1525 4225);
PAINT GREEN (1525 4225);
DISPLAY INVISIBLE (1525 4225);
FORCEPROP 1 LAST COMMENT_BODY TRUE
J 0
(1155 4255);
DISPLAY 0.872340 (1155 4255);
PAINT GREEN (1155 4255);
DISPLAY INVISIBLE (1155 4255);
FORCEADD OFFPAGE..2
(1200 4450);
FORCEPROP 2 LAST $XR1 244 
J 0
(1509 4450);
DISPLAY 0.638298 (1509 4450);
PAINT MONO (1509 4450);
FORCEPROP 2 LAST $XR0 108 
J 0
(1389 4450);
DISPLAY 0.638298 (1389 4450);
PAINT MONO (1389 4450);
FORCEPROP 2 LAST CDS_LIB mstr_standard
J 0
(1200 4450);
PAINT MONO (1200 4450);
DISPLAY INVISIBLE (1200 4450);
FORCEPROP 2 LAST PATH I75
J 0
(1525 4500);
DISPLAY 1.021277 (1525 4500);
PAINT ORANGE (1525 4500);
DISPLAY INVISIBLE (1525 4500);
FORCEPROP 1 LAST OFFPAGE TRUE
J 0
(1525 4325);
DISPLAY 0.872340 (1525 4325);
PAINT GREEN (1525 4325);
DISPLAY INVISIBLE (1525 4325);
FORCEPROP 1 LAST COMMENT_BODY TRUE
J 0
(1155 4355);
DISPLAY 0.872340 (1155 4355);
PAINT GREEN (1155 4355);
DISPLAY INVISIBLE (1155 4355);
FORCEADD TAP..1
(-50 2600);
FORCEPROP 3 LASTPIN (-100 2600) SIG_NAME P3E_CPU0_PE2_SS_RXP<3>
J 0
(-90 2610);
DISPLAY 0.659574 (-90 2610);
PAINT MONO (-90 2610);
DISPLAY INVISIBLE (-90 2610);
FORCEPROP 1 LASTPIN (-100 2600) BN 3
J 0
(-112 2608);
DISPLAY 0.617021 (-112 2608);
PAINT GREEN (-112 2608);
FORCEPROP 2 LAST CDS_LIB mstr_standard
J 0
(-50 2600);
PAINT MONO (-50 2600);
DISPLAY INVISIBLE (-50 2600);
FORCEPROP 1 LAST PATH I76
J 0
(-52 2600);
DISPLAY 0.872340 (-52 2600);
PAINT GREEN (-52 2600);
DISPLAY INVISIBLE (-52 2600);
FORCEPROP 1 LAST BODY_TYPE PLUMBING
J 0
(125 2650);
DISPLAY 0.872340 (125 2650);
PAINT GREEN (125 2650);
DISPLAY INVISIBLE (125 2650);
FORCEPROP 1 LAST HDL_TAP TRUE
J 0
(450 2475);
DISPLAY 0.872340 (450 2475);
PAINT ORANGE (450 2475);
DISPLAY INVISIBLE (450 2475);
FORCEADD TAP..1
(-275 2950);
FORCEPROP 3 LASTPIN (-325 2950) SIG_NAME P3E_CPU0_PE2_SS_RXN<1>
J 0
(-315 2960);
DISPLAY 0.659574 (-315 2960);
PAINT MONO (-315 2960);
DISPLAY INVISIBLE (-315 2960);
FORCEPROP 1 LASTPIN (-325 2950) BN 1
J 0
(-337 2958);
DISPLAY 0.617021 (-337 2958);
PAINT GREEN (-337 2958);
FORCEPROP 2 LAST CDS_LIB mstr_standard
J 0
(-275 2950);
PAINT MONO (-275 2950);
DISPLAY INVISIBLE (-275 2950);
FORCEPROP 1 LAST PATH I77
J 0
(-277 2950);
DISPLAY 0.872340 (-277 2950);
PAINT GREEN (-277 2950);
DISPLAY INVISIBLE (-277 2950);
FORCEPROP 1 LAST BODY_TYPE PLUMBING
J 0
(-100 3000);
DISPLAY 0.872340 (-100 3000);
PAINT GREEN (-100 3000);
DISPLAY INVISIBLE (-100 3000);
FORCEPROP 1 LAST HDL_TAP TRUE
J 0
(225 2825);
DISPLAY 0.872340 (225 2825);
PAINT ORANGE (225 2825);
DISPLAY INVISIBLE (225 2825);
FORCEADD SCONN200_H68296001..2
(-1000 3200);
FORCEPROP 2 LASTPIN (-1350 3250) $PN 147
J 2
(-1360 3260);
DISPLAY 0.617021 (-1360 3260);
PAINT ORANGE (-1360 3260);
FORCEPROP 2 LASTPIN (-650 3400) $PN 142
J 0
(-640 3410);
DISPLAY 0.617021 (-640 3410);
PAINT ORANGE (-640 3410);
FORCEPROP 2 LASTPIN (-650 2150) $PN 192
J 0
(-640 2160);
DISPLAY 0.617021 (-640 2160);
PAINT ORANGE (-640 2160);
FORCEPROP 2 LASTPIN (-650 3150) $PN 152
J 0
(-640 3160);
DISPLAY 0.617021 (-640 3160);
PAINT ORANGE (-640 3160);
FORCEPROP 2 LASTPIN (-1350 3000) $PN 157
J 2
(-1360 3010);
DISPLAY 0.617021 (-1360 3010);
PAINT ORANGE (-1360 3010);
FORCEPROP 2 LASTPIN (-1350 2950) $PN 159
J 2
(-1360 2960);
DISPLAY 0.617021 (-1360 2960);
PAINT ORANGE (-1360 2960);
FORCEPROP 2 LASTPIN (-1350 2350) $PN 183
J 2
(-1360 2360);
DISPLAY 0.617021 (-1360 2360);
PAINT ORANGE (-1360 2360);
FORCEPROP 2 LASTPIN (-650 3550) $PN 136
J 0
(-640 3560);
DISPLAY 0.617021 (-640 3560);
PAINT ORANGE (-640 3560);
FORCEPROP 2 LASTPIN (-650 3500) $PN 138
J 0
(-640 3510);
DISPLAY 0.617021 (-640 3510);
PAINT ORANGE (-640 3510);
FORCEPROP 2 LASTPIN (-650 3450) $PN 140
J 0
(-640 3460);
DISPLAY 0.617021 (-640 3460);
PAINT ORANGE (-640 3460);
FORCEPROP 2 LASTPIN (-650 3350) $PN 144
J 0
(-640 3360);
DISPLAY 0.617021 (-640 3360);
PAINT ORANGE (-640 3360);
FORCEPROP 2 LASTPIN (-650 3300) $PN 146
J 0
(-640 3310);
DISPLAY 0.617021 (-640 3310);
PAINT ORANGE (-640 3310);
FORCEPROP 2 LASTPIN (-650 3250) $PN 148
J 0
(-640 3260);
DISPLAY 0.617021 (-640 3260);
PAINT ORANGE (-640 3260);
FORCEPROP 1 LAST PART_NUMBER H68296-001
J 0
(-1300 1800);
DISPLAY 0.617021 (-1300 1800);
PAINT BLUE (-1300 1800);
FORCEPROP 2 LASTPIN (-1350 2250) $PN 187
J 2
(-1360 2260);
DISPLAY 0.617021 (-1360 2260);
PAINT ORANGE (-1360 2260);
FORCEPROP 2 LASTPIN (-650 2950) $PN 160
J 0
(-640 2960);
DISPLAY 0.617021 (-640 2960);
PAINT ORANGE (-640 2960);
FORCEPROP 2 LASTPIN (-650 3000) $PN 158
J 0
(-640 3010);
DISPLAY 0.617021 (-640 3010);
PAINT ORANGE (-640 3010);
FORCEPROP 2 LASTPIN (-650 2000) $PN 198
J 0
(-640 2010);
DISPLAY 0.617021 (-640 2010);
PAINT ORANGE (-640 2010);
FORCEPROP 2 LASTPIN (-650 2050) $PN 196
J 0
(-640 2060);
DISPLAY 0.617021 (-640 2060);
PAINT ORANGE (-640 2060);
FORCEPROP 2 LASTPIN (-650 2100) $PN 194
J 0
(-640 2110);
DISPLAY 0.617021 (-640 2110);
PAINT ORANGE (-640 2110);
FORCEPROP 2 LASTPIN (-650 2200) $PN 190
J 0
(-640 2210);
DISPLAY 0.617021 (-640 2210);
PAINT ORANGE (-640 2210);
FORCEPROP 2 LASTPIN (-650 2250) $PN 188
J 0
(-640 2260);
DISPLAY 0.617021 (-640 2260);
PAINT ORANGE (-640 2260);
FORCEPROP 2 LASTPIN (-650 2300) $PN 186
J 0
(-640 2310);
DISPLAY 0.617021 (-640 2310);
PAINT ORANGE (-640 2310);
FORCEPROP 2 LASTPIN (-650 2350) $PN 184
J 0
(-640 2360);
DISPLAY 0.617021 (-640 2360);
PAINT ORANGE (-640 2360);
FORCEPROP 2 LASTPIN (-650 3050) $PN 156
J 0
(-640 3060);
DISPLAY 0.617021 (-640 3060);
PAINT ORANGE (-640 3060);
FORCEPROP 2 LASTPIN (-1350 3100) $PN 153
J 2
(-1360 3110);
DISPLAY 0.617021 (-1360 3110);
PAINT ORANGE (-1360 3110);
FORCEPROP 2 LASTPIN (-1350 3050) $PN 155
J 2
(-1360 3060);
DISPLAY 0.617021 (-1360 3060);
PAINT ORANGE (-1360 3060);
FORCEPROP 2 LASTPIN (-1350 4400) $PN 101
J 2
(-1360 4410);
DISPLAY 0.617021 (-1360 4410);
PAINT ORANGE (-1360 4410);
FORCEPROP 2 LASTPIN (-1350 4350) $PN 103
J 2
(-1360 4360);
DISPLAY 0.617021 (-1360 4360);
PAINT ORANGE (-1360 4360);
FORCEPROP 2 LASTPIN (-1350 4300) $PN 105
J 2
(-1360 4310);
DISPLAY 0.617021 (-1360 4310);
PAINT ORANGE (-1360 4310);
FORCEPROP 2 LASTPIN (-650 3900) $PN 122
J 0
(-640 3910);
DISPLAY 0.617021 (-640 3910);
PAINT ORANGE (-640 3910);
FORCEPROP 2 LASTPIN (-1350 2550) $PN 175
J 2
(-1360 2560);
DISPLAY 0.617021 (-1360 2560);
PAINT ORANGE (-1360 2560);
FORCEPROP 2 LASTPIN (-1350 3150) $PN 151
J 2
(-1360 3160);
DISPLAY 0.617021 (-1360 3160);
PAINT ORANGE (-1360 3160);
FORCEPROP 2 LASTPIN (-1350 2600) $PN 173
J 2
(-1360 2610);
DISPLAY 0.617021 (-1360 2610);
PAINT ORANGE (-1360 2610);
FORCEPROP 2 LASTPIN (-1350 3200) $PN 149
J 2
(-1360 3210);
DISPLAY 0.617021 (-1360 3210);
PAINT ORANGE (-1360 3210);
FORCEPROP 2 LASTPIN (-1350 2850) $PN 163
J 2
(-1360 2860);
DISPLAY 0.617021 (-1360 2860);
PAINT ORANGE (-1360 2860);
FORCEPROP 2 LASTPIN (-1350 2800) $PN 165
J 2
(-1360 2810);
DISPLAY 0.617021 (-1360 2810);
PAINT ORANGE (-1360 2810);
FORCEPROP 2 LASTPIN (-1350 2750) $PN 167
J 2
(-1360 2760);
DISPLAY 0.617021 (-1360 2760);
PAINT ORANGE (-1360 2760);
FORCEPROP 2 LASTPIN (-1350 2700) $PN 169
J 2
(-1360 2710);
DISPLAY 0.617021 (-1360 2710);
PAINT ORANGE (-1360 2710);
FORCEPROP 2 LASTPIN (-650 1950) $PN 200
J 0
(-640 1960);
DISPLAY 0.617021 (-640 1960);
PAINT ORANGE (-640 1960);
FORCEPROP 2 LASTPIN (-650 3850) $PN 124
J 0
(-640 3860);
DISPLAY 0.617021 (-640 3860);
PAINT ORANGE (-640 3860);
FORCEPROP 2 LASTPIN (-650 3750) $PN 128
J 0
(-640 3760);
DISPLAY 0.617021 (-640 3760);
PAINT ORANGE (-640 3760);
FORCEPROP 2 LASTPIN (-650 4250) $PN 108
J 0
(-640 4260);
DISPLAY 0.617021 (-640 4260);
PAINT ORANGE (-640 4260);
FORCEPROP 2 LASTPIN (-1350 2450) $PN 179
J 2
(-1360 2460);
DISPLAY 0.617021 (-1360 2460);
PAINT ORANGE (-1360 2460);
FORCEPROP 2 LASTPIN (-1350 2500) $PN 177
J 2
(-1360 2510);
DISPLAY 0.617021 (-1360 2510);
PAINT ORANGE (-1360 2510);
FORCEPROP 2 LASTPIN (-1350 2400) $PN 181
J 2
(-1360 2410);
DISPLAY 0.617021 (-1360 2410);
PAINT ORANGE (-1360 2410);
FORCEPROP 2 LASTPIN (-1350 2300) $PN 185
J 2
(-1360 2310);
DISPLAY 0.617021 (-1360 2310);
PAINT ORANGE (-1360 2310);
FORCEPROP 2 LASTPIN (-1350 2050) $PN 195
J 2
(-1360 2060);
DISPLAY 0.617021 (-1360 2060);
PAINT ORANGE (-1360 2060);
FORCEPROP 2 LASTPIN (-1350 2000) $PN 197
J 2
(-1360 2010);
DISPLAY 0.617021 (-1360 2010);
PAINT ORANGE (-1360 2010);
FORCEPROP 2 LASTPIN (-1350 2100) $PN 193
J 2
(-1360 2110);
DISPLAY 0.617021 (-1360 2110);
PAINT ORANGE (-1360 2110);
FORCEPROP 2 LASTPIN (-1350 3400) $PN 141
J 2
(-1360 3410);
DISPLAY 0.617021 (-1360 3410);
PAINT ORANGE (-1360 3410);
FORCEPROP 2 LASTPIN (-1350 3450) $PN 139
J 2
(-1360 3460);
DISPLAY 0.617021 (-1360 3460);
PAINT ORANGE (-1360 3460);
FORCEPROP 2 LASTPIN (-1350 4250) $PN 107
J 2
(-1360 4260);
DISPLAY 0.617021 (-1360 4260);
PAINT ORANGE (-1360 4260);
FORCEPROP 2 LASTPIN (-650 4050) $PN 116
J 0
(-640 4060);
DISPLAY 0.617021 (-640 4060);
PAINT ORANGE (-640 4060);
FORCEPROP 2 LASTPIN (-650 3950) $PN 120
J 0
(-640 3960);
DISPLAY 0.617021 (-640 3960);
PAINT ORANGE (-640 3960);
FORCEPROP 2 LASTPIN (-650 4000) $PN 118
J 0
(-640 4010);
DISPLAY 0.617021 (-640 4010);
PAINT ORANGE (-640 4010);
FORCEPROP 2 LASTPIN (-1350 2200) $PN 189
J 2
(-1360 2210);
DISPLAY 0.617021 (-1360 2210);
PAINT ORANGE (-1360 2210);
FORCEPROP 2 LASTPIN (-1350 2150) $PN 191
J 2
(-1360 2160);
DISPLAY 0.617021 (-1360 2160);
PAINT ORANGE (-1360 2160);
FORCEPROP 2 LASTPIN (-1350 1950) $PN 199
J 2
(-1360 1960);
DISPLAY 0.617021 (-1360 1960);
PAINT ORANGE (-1360 1960);
FORCEPROP 2 LASTPIN (-1350 2650) $PN 171
J 2
(-1360 2660);
DISPLAY 0.617021 (-1360 2660);
PAINT ORANGE (-1360 2660);
FORCEPROP 2 LASTPIN (-650 3600) $PN 134
J 0
(-640 3610);
DISPLAY 0.617021 (-640 3610);
PAINT ORANGE (-640 3610);
FORCEPROP 2 LASTPIN (-1350 4200) $PN 109
J 2
(-1360 4210);
DISPLAY 0.617021 (-1360 4210);
PAINT ORANGE (-1360 4210);
FORCEPROP 2 LASTPIN (-650 3800) $PN 126
J 0
(-640 3810);
DISPLAY 0.617021 (-640 3810);
PAINT ORANGE (-640 3810);
FORCEPROP 2 LASTPIN (-650 3700) $PN 130
J 0
(-640 3710);
DISPLAY 0.617021 (-640 3710);
PAINT ORANGE (-640 3710);
FORCEPROP 2 LASTPIN (-650 3650) $PN 132
J 0
(-640 3660);
DISPLAY 0.617021 (-640 3660);
PAINT ORANGE (-640 3660);
FORCEPROP 2 LASTPIN (-1350 4050) $PN 115
J 2
(-1360 4060);
DISPLAY 0.617021 (-1360 4060);
PAINT ORANGE (-1360 4060);
FORCEPROP 2 LASTPIN (-1350 4000) $PN 117
J 2
(-1360 4010);
DISPLAY 0.617021 (-1360 4010);
PAINT ORANGE (-1360 4010);
FORCEPROP 2 LASTPIN (-1350 3950) $PN 119
J 2
(-1360 3960);
DISPLAY 0.617021 (-1360 3960);
PAINT ORANGE (-1360 3960);
FORCEPROP 2 LASTPIN (-1350 3900) $PN 121
J 2
(-1360 3910);
DISPLAY 0.617021 (-1360 3910);
PAINT ORANGE (-1360 3910);
FORCEPROP 2 LASTPIN (-1350 3800) $PN 125
J 2
(-1360 3810);
DISPLAY 0.617021 (-1360 3810);
PAINT ORANGE (-1360 3810);
FORCEPROP 2 LASTPIN (-1350 3750) $PN 127
J 2
(-1360 3760);
DISPLAY 0.617021 (-1360 3760);
PAINT ORANGE (-1360 3760);
FORCEPROP 2 LASTPIN (-1350 3700) $PN 129
J 2
(-1360 3710);
DISPLAY 0.617021 (-1360 3710);
PAINT ORANGE (-1360 3710);
FORCEPROP 2 LASTPIN (-1350 3650) $PN 131
J 2
(-1360 3660);
DISPLAY 0.617021 (-1360 3660);
PAINT ORANGE (-1360 3660);
FORCEPROP 2 LASTPIN (-1350 3600) $PN 133
J 2
(-1360 3610);
DISPLAY 0.617021 (-1360 3610);
PAINT ORANGE (-1360 3610);
FORCEPROP 2 LASTPIN (-1350 3550) $PN 135
J 2
(-1360 3560);
DISPLAY 0.617021 (-1360 3560);
PAINT ORANGE (-1360 3560);
FORCEPROP 2 LASTPIN (-1350 3500) $PN 137
J 2
(-1360 3510);
DISPLAY 0.617021 (-1360 3510);
PAINT ORANGE (-1360 3510);
FORCEPROP 2 LASTPIN (-1350 3350) $PN 143
J 2
(-1360 3360);
DISPLAY 0.617021 (-1360 3360);
PAINT ORANGE (-1360 3360);
FORCEPROP 2 LASTPIN (-1350 3300) $PN 145
J 2
(-1360 3310);
DISPLAY 0.617021 (-1360 3310);
PAINT ORANGE (-1360 3310);
FORCEPROP 2 LASTPIN (-1350 2900) $PN 161
J 2
(-1360 2910);
DISPLAY 0.617021 (-1360 2910);
PAINT ORANGE (-1360 2910);
FORCEPROP 2 LASTPIN (-650 3200) $PN 150
J 0
(-640 3210);
DISPLAY 0.617021 (-640 3210);
PAINT ORANGE (-640 3210);
FORCEPROP 2 LASTPIN (-650 3100) $PN 154
J 0
(-640 3110);
DISPLAY 0.617021 (-640 3110);
PAINT ORANGE (-640 3110);
FORCEPROP 2 LASTPIN (-650 2900) $PN 162
J 0
(-640 2910);
DISPLAY 0.617021 (-640 2910);
PAINT ORANGE (-640 2910);
FORCEPROP 2 LASTPIN (-650 2750) $PN 168
J 0
(-640 2760);
DISPLAY 0.617021 (-640 2760);
PAINT ORANGE (-640 2760);
FORCEPROP 2 LASTPIN (-650 2650) $PN 172
J 0
(-640 2660);
DISPLAY 0.617021 (-640 2660);
PAINT ORANGE (-640 2660);
FORCEPROP 2 LASTPIN (-650 2850) $PN 164
J 0
(-640 2860);
DISPLAY 0.617021 (-640 2860);
PAINT ORANGE (-640 2860);
FORCEPROP 2 LASTPIN (-650 2600) $PN 174
J 0
(-640 2610);
DISPLAY 0.617021 (-640 2610);
PAINT ORANGE (-640 2610);
FORCEPROP 2 LASTPIN (-650 2700) $PN 170
J 0
(-640 2710);
DISPLAY 0.617021 (-640 2710);
PAINT ORANGE (-640 2710);
FORCEPROP 2 LASTPIN (-650 2550) $PN 176
J 0
(-640 2560);
DISPLAY 0.617021 (-640 2560);
PAINT ORANGE (-640 2560);
FORCEPROP 2 LASTPIN (-650 2500) $PN 178
J 0
(-640 2510);
DISPLAY 0.617021 (-640 2510);
PAINT ORANGE (-640 2510);
FORCEPROP 2 LASTPIN (-650 2450) $PN 180
J 0
(-640 2460);
DISPLAY 0.617021 (-640 2460);
PAINT ORANGE (-640 2460);
FORCEPROP 2 LASTPIN (-650 2400) $PN 182
J 0
(-640 2410);
DISPLAY 0.617021 (-640 2410);
PAINT ORANGE (-640 2410);
FORCEPROP 2 LASTPIN (-650 2800) $PN 166
J 0
(-640 2810);
DISPLAY 0.617021 (-640 2810);
PAINT ORANGE (-640 2810);
FORCEPROP 2 LASTPIN (-650 4300) $PN 106
J 0
(-640 4310);
DISPLAY 0.617021 (-640 4310);
PAINT ORANGE (-640 4310);
FORCEPROP 2 LASTPIN (-650 4350) $PN 104
J 0
(-640 4360);
DISPLAY 0.617021 (-640 4360);
PAINT ORANGE (-640 4360);
FORCEPROP 2 LASTPIN (-650 4400) $PN 102
J 0
(-640 4410);
DISPLAY 0.617021 (-640 4410);
PAINT ORANGE (-640 4410);
FORCEPROP 2 LASTPIN (-650 4100) $PN 114
J 0
(-640 4110);
DISPLAY 0.617021 (-640 4110);
PAINT ORANGE (-640 4110);
FORCEPROP 2 LASTPIN (-650 4150) $PN 112
J 0
(-640 4160);
DISPLAY 0.617021 (-640 4160);
PAINT ORANGE (-640 4160);
FORCEPROP 2 LASTPIN (-650 4200) $PN 110
J 0
(-640 4210);
DISPLAY 0.617021 (-640 4210);
PAINT ORANGE (-640 4210);
FORCEPROP 2 LASTPIN (-1350 4100) $PN 113
J 2
(-1360 4110);
DISPLAY 0.617021 (-1360 4110);
PAINT ORANGE (-1360 4110);
FORCEPROP 1 LAST MATERIAL CONN
J 0
(-1300 4650);
DISPLAY 0.617021 (-1300 4650);
PAINT SKYBLUE (-1300 4650);
FORCEPROP 1 LAST LOCATION J8G1
J 0
(-1325 4700);
DISPLAY 0.617021 (-1325 4700);
PAINT AQUA (-1325 4700);
FORCEPROP 2 LASTPIN (-1350 3850) $PN 123
J 2
(-1360 3860);
DISPLAY 0.617021 (-1360 3860);
PAINT ORANGE (-1360 3860);
FORCEPROP 2 LASTPIN (-1350 4150) $PN 111
J 2
(-1360 4160);
DISPLAY 0.617021 (-1360 4160);
PAINT ORANGE (-1360 4160);
FORCEPROP 1 LAST PATH I78
J 0
(-900 4650);
PAINT GREEN (-900 4650);
DISPLAY INVISIBLE (-900 4650);
FORCEPROP 1 LAST PACK_TYPE SM
J 0
(-1300 4750);
PAINT SKYBLUE (-1300 4750);
DISPLAY INVISIBLE (-1300 4750);
FORCEPROP 0 LAST ROOM IO_SLOT
J 0
(-1300 4725);
DISPLAY 1.021277 (-1300 4725);
PAINT ORANGE (-1300 4725);
DISPLAY INVISIBLE (-1300 4725);
FORCEPROP 2 LAST SEC_TYPE SM
J 0
(-900 4700);
DISPLAY 1.021277 (-900 4700);
PAINT ORANGE (-900 4700);
DISPLAY INVISIBLE (-900 4700);
FORCEPROP 2 LAST CDS_LIB mstr_sconn
J 0
(-1000 3200);
PAINT MONO (-1000 3200);
DISPLAY INVISIBLE (-1000 3200);
FORCEPROP 1 LAST CDS_LMAN_SYM_OUTLINE -300,1350,300,-1350
J 0
(-1000 3200);
DISPLAY 0.468085 (-1000 3200);
PAINT GREEN (-1000 3200);
DISPLAY INVISIBLE (-1000 3200);
FORCEPROP 2 LAST SEC 2
J 0
(-900 4700);
DISPLAY 0.680851 (-900 4700);
PAINT MONO (-900 4700);
DISPLAY INVISIBLE (-900 4700);
FORCEADD TAP..1
R 2
(-2050 2050);
FORCEPROP 3 LASTPIN (-2000 2050) SIG_NAME P3E_CPU0_PE2_SS_C_TXP<7>
J 0
(-1990 2060);
DISPLAY 0.659574 (-1990 2060);
PAINT MONO (-1990 2060);
DISPLAY INVISIBLE (-1990 2060);
FORCEPROP 1 LASTPIN (-2000 2050) BN 7
J 2
(-1988 2058);
DISPLAY 0.617021 (-1988 2058);
PAINT GREEN (-1988 2058);
FORCEPROP 2 LAST CDS_LIB mstr_standard
J 0
(-2050 2050);
PAINT MONO (-2050 2050);
DISPLAY INVISIBLE (-2050 2050);
FORCEPROP 1 LAST PATH I8
J 2
(-2048 2050);
DISPLAY 0.872340 (-2048 2050);
PAINT GREEN (-2048 2050);
DISPLAY INVISIBLE (-2048 2050);
FORCEPROP 1 LAST BODY_TYPE PLUMBING
J 2
(-2050 2100);
DISPLAY 0.872340 (-2050 2100);
PAINT GREEN (-2050 2100);
DISPLAY INVISIBLE (-2050 2100);
FORCEPROP 1 LAST HDL_TAP TRUE
J 2
(-2375 1925);
DISPLAY 0.872340 (-2375 1925);
PAINT ORANGE (-2375 1925);
DISPLAY INVISIBLE (-2375 1925);
FORCEADD TAP..1
(-275 2800);
FORCEPROP 3 LASTPIN (-325 2800) SIG_NAME P3E_CPU0_PE2_SS_RXN<2>
J 0
(-315 2810);
DISPLAY 0.659574 (-315 2810);
PAINT MONO (-315 2810);
DISPLAY INVISIBLE (-315 2810);
FORCEPROP 1 LASTPIN (-325 2800) BN 2
J 0
(-337 2808);
DISPLAY 0.617021 (-337 2808);
PAINT GREEN (-337 2808);
FORCEPROP 2 LAST CDS_LIB mstr_standard
J 0
(-275 2800);
PAINT MONO (-275 2800);
DISPLAY INVISIBLE (-275 2800);
FORCEPROP 1 LAST PATH I80
J 0
(-277 2800);
DISPLAY 0.872340 (-277 2800);
PAINT GREEN (-277 2800);
DISPLAY INVISIBLE (-277 2800);
FORCEPROP 1 LAST BODY_TYPE PLUMBING
J 0
(-100 2850);
DISPLAY 0.872340 (-100 2850);
PAINT GREEN (-100 2850);
DISPLAY INVISIBLE (-100 2850);
FORCEPROP 1 LAST HDL_TAP TRUE
J 0
(225 2675);
DISPLAY 0.872340 (225 2675);
PAINT ORANGE (225 2675);
DISPLAY INVISIBLE (225 2675);
FORCEADD TAP..1
(-50 2750);
FORCEPROP 3 LASTPIN (-100 2750) SIG_NAME P3E_CPU0_PE2_SS_RXP<2>
J 0
(-90 2760);
DISPLAY 0.659574 (-90 2760);
PAINT MONO (-90 2760);
DISPLAY INVISIBLE (-90 2760);
FORCEPROP 1 LASTPIN (-100 2750) BN 2
J 0
(-112 2758);
DISPLAY 0.617021 (-112 2758);
PAINT GREEN (-112 2758);
FORCEPROP 2 LAST CDS_LIB mstr_standard
J 0
(-50 2750);
PAINT MONO (-50 2750);
DISPLAY INVISIBLE (-50 2750);
FORCEPROP 1 LAST PATH I81
J 0
(-52 2750);
DISPLAY 0.872340 (-52 2750);
PAINT GREEN (-52 2750);
DISPLAY INVISIBLE (-52 2750);
FORCEPROP 1 LAST BODY_TYPE PLUMBING
J 0
(125 2800);
DISPLAY 0.872340 (125 2800);
PAINT GREEN (125 2800);
DISPLAY INVISIBLE (125 2800);
FORCEPROP 1 LAST HDL_TAP TRUE
J 0
(450 2625);
DISPLAY 0.872340 (450 2625);
PAINT ORANGE (450 2625);
DISPLAY INVISIBLE (450 2625);
FORCEADD TAP..1
R 2
(-2050 3450);
FORCEPROP 3 LASTPIN (-2000 3450) SIG_NAME P3E_CPU0_PE1_SS_C_TXN<1>
J 0
(-1990 3460);
DISPLAY 0.659574 (-1990 3460);
PAINT MONO (-1990 3460);
DISPLAY INVISIBLE (-1990 3460);
FORCEPROP 1 LASTPIN (-2000 3450) BN 1
J 2
(-1988 3458);
DISPLAY 0.617021 (-1988 3458);
PAINT GREEN (-1988 3458);
FORCEPROP 2 LAST CDS_LIB mstr_standard
J 0
(-2050 3450);
PAINT MONO (-2050 3450);
DISPLAY INVISIBLE (-2050 3450);
FORCEPROP 1 LAST PATH I82
J 2
(-2048 3450);
DISPLAY 0.872340 (-2048 3450);
PAINT GREEN (-2048 3450);
DISPLAY INVISIBLE (-2048 3450);
FORCEPROP 1 LAST BODY_TYPE PLUMBING
J 2
(-2050 3500);
DISPLAY 0.872340 (-2050 3500);
PAINT GREEN (-2050 3500);
DISPLAY INVISIBLE (-2050 3500);
FORCEPROP 1 LAST HDL_TAP TRUE
J 2
(-2375 3325);
DISPLAY 0.872340 (-2375 3325);
PAINT ORANGE (-2375 3325);
DISPLAY INVISIBLE (-2375 3325);
FORCEADD TAP..1
R 2
(-2300 3400);
FORCEPROP 3 LASTPIN (-2250 3400) SIG_NAME P3E_CPU0_PE1_SS_C_TXP<1>
J 0
(-2240 3410);
DISPLAY 0.659574 (-2240 3410);
PAINT MONO (-2240 3410);
DISPLAY INVISIBLE (-2240 3410);
FORCEPROP 1 LASTPIN (-2250 3400) BN 1
J 2
(-2238 3408);
DISPLAY 0.617021 (-2238 3408);
PAINT GREEN (-2238 3408);
FORCEPROP 1 LAST PATH I83
J 2
(-2298 3400);
DISPLAY 0.872340 (-2298 3400);
PAINT GREEN (-2298 3400);
DISPLAY INVISIBLE (-2298 3400);
FORCEPROP 2 LAST CDS_LIB mstr_standard
J 0
(-2300 3400);
PAINT MONO (-2300 3400);
DISPLAY INVISIBLE (-2300 3400);
FORCEPROP 1 LAST BODY_TYPE PLUMBING
J 2
(-2300 3450);
DISPLAY 0.872340 (-2300 3450);
PAINT GREEN (-2300 3450);
DISPLAY INVISIBLE (-2300 3450);
FORCEPROP 1 LAST HDL_TAP TRUE
J 2
(-2625 3275);
DISPLAY 0.872340 (-2625 3275);
PAINT ORANGE (-2625 3275);
DISPLAY INVISIBLE (-2625 3275);
FORCEADD TAP..1
R 2
(-2050 3900);
FORCEPROP 3 LASTPIN (-2000 3900) SIG_NAME P3E_CPU0_PE1_SS_C_TXN<4>
J 0
(-1990 3910);
DISPLAY 0.659574 (-1990 3910);
PAINT MONO (-1990 3910);
DISPLAY INVISIBLE (-1990 3910);
FORCEPROP 1 LASTPIN (-2000 3900) BN 4
J 2
(-1988 3908);
DISPLAY 0.617021 (-1988 3908);
PAINT GREEN (-1988 3908);
FORCEPROP 1 LAST PATH I84
J 2
(-2048 3900);
DISPLAY 0.872340 (-2048 3900);
PAINT GREEN (-2048 3900);
DISPLAY INVISIBLE (-2048 3900);
FORCEPROP 2 LAST CDS_LIB mstr_standard
J 0
(-2050 3900);
PAINT MONO (-2050 3900);
DISPLAY INVISIBLE (-2050 3900);
FORCEPROP 1 LAST BODY_TYPE PLUMBING
J 2
(-2050 3950);
DISPLAY 0.872340 (-2050 3950);
PAINT GREEN (-2050 3950);
DISPLAY INVISIBLE (-2050 3950);
FORCEPROP 1 LAST HDL_TAP TRUE
J 2
(-2375 3775);
DISPLAY 0.872340 (-2375 3775);
PAINT ORANGE (-2375 3775);
DISPLAY INVISIBLE (-2375 3775);
FORCEADD TAP..1
R 2
(-2300 3850);
FORCEPROP 3 LASTPIN (-2250 3850) SIG_NAME P3E_CPU0_PE1_SS_C_TXP<4>
J 0
(-2240 3860);
DISPLAY 0.659574 (-2240 3860);
PAINT MONO (-2240 3860);
DISPLAY INVISIBLE (-2240 3860);
FORCEPROP 1 LASTPIN (-2250 3850) BN 4
J 2
(-2238 3858);
DISPLAY 0.617021 (-2238 3858);
PAINT GREEN (-2238 3858);
FORCEPROP 1 LAST PATH I85
J 2
(-2298 3850);
DISPLAY 0.872340 (-2298 3850);
PAINT GREEN (-2298 3850);
DISPLAY INVISIBLE (-2298 3850);
FORCEPROP 2 LAST CDS_LIB mstr_standard
J 0
(-2300 3850);
PAINT MONO (-2300 3850);
DISPLAY INVISIBLE (-2300 3850);
FORCEPROP 1 LAST BODY_TYPE PLUMBING
J 2
(-2300 3900);
DISPLAY 0.872340 (-2300 3900);
PAINT GREEN (-2300 3900);
DISPLAY INVISIBLE (-2300 3900);
FORCEPROP 1 LAST HDL_TAP TRUE
J 2
(-2625 3725);
DISPLAY 0.872340 (-2625 3725);
PAINT ORANGE (-2625 3725);
DISPLAY INVISIBLE (-2625 3725);
FORCEADD TAP..1
(-275 3550);
FORCEPROP 3 LASTPIN (-325 3550) SIG_NAME P3E_CPU0_PE1_SS_R_RXN<2>
J 0
(-315 3560);
DISPLAY 0.659574 (-315 3560);
PAINT MONO (-315 3560);
DISPLAY INVISIBLE (-315 3560);
FORCEPROP 1 LASTPIN (-325 3550) BN 2
J 0
(-337 3558);
DISPLAY 0.617021 (-337 3558);
PAINT GREEN (-337 3558);
FORCEPROP 2 LAST CDS_LIB mstr_standard
J 0
(-275 3550);
PAINT MONO (-275 3550);
DISPLAY INVISIBLE (-275 3550);
FORCEPROP 1 LAST PATH I86
J 0
(-277 3550);
DISPLAY 0.872340 (-277 3550);
PAINT GREEN (-277 3550);
DISPLAY INVISIBLE (-277 3550);
FORCEPROP 1 LAST BODY_TYPE PLUMBING
J 0
(-100 3600);
DISPLAY 0.872340 (-100 3600);
PAINT GREEN (-100 3600);
DISPLAY INVISIBLE (-100 3600);
FORCEPROP 1 LAST HDL_TAP TRUE
J 0
(225 3425);
DISPLAY 0.872340 (225 3425);
PAINT ORANGE (225 3425);
DISPLAY INVISIBLE (225 3425);
FORCEADD TAP..1
(-50 3500);
FORCEPROP 3 LASTPIN (-100 3500) SIG_NAME P3E_CPU0_PE1_SS_R_RXP<2>
J 0
(-90 3510);
DISPLAY 0.659574 (-90 3510);
PAINT MONO (-90 3510);
DISPLAY INVISIBLE (-90 3510);
FORCEPROP 1 LASTPIN (-100 3500) BN 2
J 0
(-112 3508);
DISPLAY 0.617021 (-112 3508);
PAINT GREEN (-112 3508);
FORCEPROP 2 LAST CDS_LIB mstr_standard
J 0
(-50 3500);
PAINT MONO (-50 3500);
DISPLAY INVISIBLE (-50 3500);
FORCEPROP 1 LAST PATH I87
J 0
(-52 3500);
DISPLAY 0.872340 (-52 3500);
PAINT GREEN (-52 3500);
DISPLAY INVISIBLE (-52 3500);
FORCEPROP 1 LAST BODY_TYPE PLUMBING
J 0
(125 3550);
DISPLAY 0.872340 (125 3550);
PAINT GREEN (125 3550);
DISPLAY INVISIBLE (125 3550);
FORCEPROP 1 LAST HDL_TAP TRUE
J 0
(450 3375);
DISPLAY 0.872340 (450 3375);
PAINT ORANGE (450 3375);
DISPLAY INVISIBLE (450 3375);
FORCEADD TAP..1
R 2
(-2050 4300);
FORCEPROP 3 LASTPIN (-2000 4300) SIG_NAME P3E_CPU0_PE1_SS_C_TXN<7>
J 0
(-1990 4310);
DISPLAY 0.659574 (-1990 4310);
PAINT MONO (-1990 4310);
DISPLAY INVISIBLE (-1990 4310);
FORCEPROP 1 LASTPIN (-2000 4300) BN 7
J 2
(-1988 4308);
DISPLAY 0.617021 (-1988 4308);
PAINT GREEN (-1988 4308);
FORCEPROP 2 LAST CDS_LIB mstr_standard
J 2
(-2050 4300);
PAINT ORANGE (-2050 4300);
DISPLAY INVISIBLE (-2050 4300);
FORCEPROP 1 LAST PATH I88
J 2
(-2048 4300);
DISPLAY 0.872340 (-2048 4300);
PAINT GREEN (-2048 4300);
DISPLAY INVISIBLE (-2048 4300);
FORCEPROP 1 LAST BODY_TYPE PLUMBING
J 2
(-2050 4350);
DISPLAY 0.872340 (-2050 4350);
PAINT GREEN (-2050 4350);
DISPLAY INVISIBLE (-2050 4350);
FORCEPROP 1 LAST HDL_TAP TRUE
J 2
(-2375 4175);
DISPLAY 0.872340 (-2375 4175);
PAINT ORANGE (-2375 4175);
DISPLAY INVISIBLE (-2375 4175);
FORCEADD TAP..1
R 2
(-2300 4350);
FORCEPROP 3 LASTPIN (-2250 4350) SIG_NAME P3E_CPU0_PE1_SS_C_TXP<7>
J 0
(-2240 4360);
DISPLAY 0.659574 (-2240 4360);
PAINT MONO (-2240 4360);
DISPLAY INVISIBLE (-2240 4360);
FORCEPROP 1 LASTPIN (-2250 4350) BN 7
J 2
(-2238 4358);
DISPLAY 0.617021 (-2238 4358);
PAINT GREEN (-2238 4358);
FORCEPROP 2 LAST CDS_LIB mstr_standard
J 2
(-2300 4350);
PAINT ORANGE (-2300 4350);
DISPLAY INVISIBLE (-2300 4350);
FORCEPROP 1 LAST PATH I89
J 2
(-2298 4350);
DISPLAY 0.872340 (-2298 4350);
PAINT GREEN (-2298 4350);
DISPLAY INVISIBLE (-2298 4350);
FORCEPROP 1 LAST BODY_TYPE PLUMBING
J 2
(-2300 4400);
DISPLAY 0.872340 (-2300 4400);
PAINT GREEN (-2300 4400);
DISPLAY INVISIBLE (-2300 4400);
FORCEPROP 1 LAST HDL_TAP TRUE
J 2
(-2625 4225);
DISPLAY 0.872340 (-2625 4225);
PAINT ORANGE (-2625 4225);
DISPLAY INVISIBLE (-2625 4225);
FORCEADD TAP..1
R 2
(-2050 2200);
FORCEPROP 3 LASTPIN (-2000 2200) SIG_NAME P3E_CPU0_PE2_SS_C_TXP<6>
J 0
(-1990 2210);
DISPLAY 0.659574 (-1990 2210);
PAINT MONO (-1990 2210);
DISPLAY INVISIBLE (-1990 2210);
FORCEPROP 1 LASTPIN (-2000 2200) BN 6
J 2
(-1988 2208);
DISPLAY 0.617021 (-1988 2208);
PAINT GREEN (-1988 2208);
FORCEPROP 2 LAST CDS_LIB mstr_standard
J 0
(-2050 2200);
PAINT MONO (-2050 2200);
DISPLAY INVISIBLE (-2050 2200);
FORCEPROP 1 LAST PATH I9
J 2
(-2048 2200);
DISPLAY 0.872340 (-2048 2200);
PAINT GREEN (-2048 2200);
DISPLAY INVISIBLE (-2048 2200);
FORCEPROP 1 LAST BODY_TYPE PLUMBING
J 2
(-2050 2250);
DISPLAY 0.872340 (-2050 2250);
PAINT GREEN (-2050 2250);
DISPLAY INVISIBLE (-2050 2250);
FORCEPROP 1 LAST HDL_TAP TRUE
J 2
(-2375 2075);
DISPLAY 0.872340 (-2375 2075);
PAINT ORANGE (-2375 2075);
DISPLAY INVISIBLE (-2375 2075);
FORCEADD INTEL_CORP_BPAGE..1
(2650 500);
FORCEPROP 1 LAST CDS_CON_LAST_MODIFIED Fri Jun 16 17:48:43 2017
J 0
(1225 825);
PAINT ORANGE (1225 825);
DISPLAY INVISIBLE (1225 825);
FORCEPROP 1 LAST CUSTOM_TXT_CDS <CURRENT_DESIGN_SHEET> OF <TOTAL_DESIGN_SHEETS>
J 0
(2150 525);
PAINT ORANGE (2150 525);
FORCEPROP 1 LAST CUSTOM_TXT_CDS <CON_LAST_MODIFIED>
J 0
(-1350 600);
PAINT ORANGE (-1350 600);
FORCEPROP 2 LAST CUSTOM_TXT_CDS <XR_PAGE_TITLE>
J 0
(-5240 5750);
DISPLAY 0.638298 (-5240 5750);
PAINT PINK (-5240 5750);
DISPLAY INVISIBLE (-5240 5750);
FORCEPROP 1 LAST SCH_TITLE X24 SLOT (2 OF 2)
J 0
(-5300 550);
DISPLAY 1.212766 (-5300 550);
PAINT ORANGE (-5300 550);
FORCEPROP 2 LAST PAGE_BORDER TRUE
J 0
(-5240 5750);
DISPLAY 0.851064 (-5240 5750);
PAINT PINK (-5240 5750);
DISPLAY INVISIBLE (-5240 5750);
FORCEPROP 2 LAST CDS_LIB mstr_symbols
J 0
(2650 500);
PAINT MONO (2650 500);
DISPLAY INVISIBLE (2650 500);
FORCEPROP 1 LAST COMMENT_BODY TRUE
J 0
(2662 512);
DISPLAY 0.468085 (2662 512);
PAINT GREEN (2662 512);
DISPLAY INVISIBLE (2662 512);
FORCEPROP 2 LAST CDS_XR_PAGE_TITLE CR-109 : @BASEBOARD_FAB2_LIB.BASEBOARD_FAB2(SCH_1):PAGE109
J 0
(-5240 5750);
DISPLAY 0.638298 (-5240 5750);
PAINT PINK (-5240 5750);
DISPLAY INVISIBLE (-5240 5750);
WIRE 16 -1 (-1525 2000)(-1525 1750);
WIRE 16 -1 (-1525 2150)(-1525 2000);
WIRE 16 -1 (-1350 2000)(-1525 2000);
WIRE 16 -1 (-1525 2300)(-1525 2150);
WIRE 16 -1 (-1350 2150)(-1525 2150);
WIRE 16 -1 (-1525 2450)(-1525 2300);
WIRE 16 -1 (-1350 2300)(-1525 2300);
WIRE 16 -1 (-1525 2600)(-1525 2450);
WIRE 16 -1 (-1350 2450)(-1525 2450);
WIRE 16 -1 (-1525 2750)(-1525 2600);
WIRE 16 -1 (-1350 2600)(-1525 2600);
WIRE 16 -1 (-1525 2900)(-1525 2750);
WIRE 16 -1 (-1350 2750)(-1525 2750);
WIRE 16 -1 (-1525 3050)(-1525 2900);
WIRE 16 -1 (-1350 2900)(-1525 2900);
WIRE 16 -1 (-1525 3200)(-1525 3050);
WIRE 16 -1 (-1350 3050)(-1525 3050);
WIRE 16 -1 (-1525 3350)(-1525 3200);
WIRE 16 -1 (-1350 3200)(-1525 3200);
WIRE 16 -1 (-1525 3500)(-1525 3350);
WIRE 16 -1 (-1350 3350)(-1525 3350);
WIRE 16 -1 (-1525 3650)(-1525 3500);
WIRE 16 -1 (-1350 3500)(-1525 3500);
WIRE 16 -1 (-1525 3800)(-1525 3650);
WIRE 16 -1 (-1350 3650)(-1525 3650);
WIRE 16 -1 (-1525 3950)(-1525 3800);
WIRE 16 -1 (-1350 3800)(-1525 3800);
WIRE 16 -1 (-1525 4100)(-1525 3950);
WIRE 16 -1 (-1350 3950)(-1525 3950);
WIRE 16 -1 (-1525 4250)(-1525 4100);
WIRE 16 -1 (-1350 4100)(-1525 4100);
WIRE 16 -1 (-1525 4400)(-1525 4250);
WIRE 16 -1 (-1350 4250)(-1525 4250);
WIRE 16 -1 (-1350 4400)(-1525 4400);
WIRE 16 -1 (-475 1950)(-475 1750);
WIRE 16 -1 (-475 2100)(-475 1950);
WIRE 16 -1 (-475 1950)(-650 1950);
WIRE 16 -1 (-475 2250)(-475 2100);
WIRE 16 -1 (-475 2100)(-650 2100);
WIRE 16 -1 (-475 2400)(-475 2250);
WIRE 16 -1 (-475 2250)(-650 2250);
WIRE 16 -1 (-475 2550)(-475 2400);
WIRE 16 -1 (-475 2400)(-650 2400);
WIRE 16 -1 (-475 2700)(-475 2550);
WIRE 16 -1 (-475 2550)(-650 2550);
WIRE 16 -1 (-475 2850)(-475 2700);
WIRE 16 -1 (-475 2700)(-650 2700);
WIRE 16 -1 (-475 3000)(-475 2850);
WIRE 16 -1 (-475 2850)(-650 2850);
WIRE 16 -1 (-475 3150)(-475 3000);
WIRE 16 -1 (-475 3000)(-650 3000);
WIRE 16 -1 (-475 3300)(-475 3150);
WIRE 16 -1 (-475 3150)(-650 3150);
WIRE 16 -1 (-475 3450)(-475 3300);
WIRE 16 -1 (-475 3300)(-650 3300);
WIRE 16 -1 (-475 3600)(-475 3450);
WIRE 16 -1 (-475 3450)(-650 3450);
WIRE 16 -1 (-475 3750)(-475 3600);
WIRE 16 -1 (-475 3600)(-650 3600);
WIRE 16 -1 (-475 3900)(-475 3750);
WIRE 16 -1 (-475 3750)(-650 3750);
WIRE 16 -1 (-475 4050)(-475 3900);
WIRE 16 -1 (-475 3900)(-650 3900);
WIRE 16 -1 (-475 4200)(-475 4050);
WIRE 16 -1 (-475 4050)(-650 4050);
WIRE 16 -1 (-475 4350)(-475 4200);
WIRE 16 -1 (-475 4200)(-650 4200);
WIRE 16 -1 (-650 4350)(-475 4350);
WIRE 17 -1 (0 3375)(0 3225);
WIRE 17 -1 (0 3375)(0 3525);
WIRE 17 -1 (0 3525)(0 3675);
WIRE 17 -1 (0 3825)(0 3675);
WIRE 17 -1 (0 4300)(1150 4300);
FORCEPROP 2 LAST SIG_NAME P3E_CPU0_PE1_SS_R_RXP<7:0>
J 0
(65 4310);
DISPLAY 0.680851 (65 4310);
PAINT ORANGE (65 4310);
WIRE 17 -1 (0 3975)(0 3825);
WIRE 17 -1 (0 4125)(0 3975);
WIRE 17 -1 (0 4300)(0 4275);
WIRE 17 -1 (0 4275)(0 4125);
WIRE 17 -1 (-225 4450)(1150 4450);
FORCEPROP 2 LAST SIG_NAME P3E_CPU0_PE1_PCH_CON_RXP<15:8>
J 0
(65 4460);
DISPLAY 0.680851 (65 4460);
PAINT ORANGE (65 4460);
WIRE 17 -1 (-225 4450)(-225 4425);
WIRE 17 -1 (-225 3425)(-225 3275);
WIRE 17 -1 (-225 3575)(-225 3425);
WIRE 17 -1 (-225 3725)(-225 3575);
WIRE 17 -1 (-225 3875)(-225 3725);
WIRE 17 -1 (-225 4350)(1150 4350);
FORCEPROP 2 LAST SIG_NAME P3E_CPU0_PE1_SS_R_RXN<7:0>
J 0
(65 4360);
DISPLAY 0.680851 (65 4360);
PAINT ORANGE (65 4360);
WIRE 17 -1 (-225 4025)(-225 3875);
WIRE 17 -1 (-225 4175)(-225 4025);
WIRE 17 -1 (-225 4350)(-225 4325);
WIRE 17 -1 (-225 4325)(-225 4175);
WIRE 17 -1 (-2100 3325)(-2100 3475);
WIRE 17 -1 (-2100 3475)(-2100 3625);
WIRE 17 -1 (-2100 3775)(-2100 3625);
WIRE 17 -1 (-2100 3775)(-2100 3925);
WIRE 17 -1 (-2100 3925)(-2100 4075);
WIRE 17 -1 (-3450 4450)(-2100 4450);
FORCEPROP 2 LAST SIG_NAME P3E_CPU0_PE1_SS_C_TXN<7:0>
J 0
(-3396 4470);
DISPLAY 0.680851 (-3396 4470);
PAINT ORANGE (-3396 4470);
WIRE 17 -1 (-2100 4325)(-2100 4450);
WIRE 17 -1 (-2100 4225)(-2100 4075);
WIRE 17 -1 (-2100 4225)(-2100 4325);
WIRE 17 -1 (-225 2175)(-225 2075);
WIRE 17 -1 (-225 2375)(-225 2175);
WIRE 17 -1 (-225 2525)(-225 2375);
WIRE 17 -1 (-225 2675)(-225 2525);
WIRE 17 -1 (-225 2825)(-225 2675);
WIRE 17 -1 (-225 2975)(-225 2825);
WIRE 17 -1 (-225 3125)(-225 2975);
WIRE 17 -1 (-225 3150)(1150 3150);
FORCEPROP 2 LAST SIG_NAME P3E_CPU0_PE2_SS_RXN<7:0>
J 0
(65 3160);
DISPLAY 0.617021 (65 3160);
PAINT ORANGE (65 3160);
WIRE 17 -1 (-225 3150)(-225 3125);
WIRE 17 -1 (0 2225)(0 2025);
WIRE 17 -1 (0 2325)(0 2225);
WIRE 17 -1 (0 2475)(0 2325);
WIRE 17 -1 (0 2625)(0 2475);
WIRE 17 -1 (1150 3100)(0 3100);
FORCEPROP 2 LAST SIG_NAME P3E_CPU0_PE2_SS_RXP<7:0>
J 0
(65 3110);
DISPLAY 0.617021 (65 3110);
PAINT ORANGE (65 3110);
WIRE 17 -1 (0 2625)(0 2775);
WIRE 17 -1 (0 2775)(0 2925);
WIRE 17 -1 (0 3100)(0 3075);
WIRE 17 -1 (0 3075)(0 2925);
WIRE 17 -1 (-3450 4400)(-2350 4400);
FORCEPROP 2 LAST SIG_NAME P3E_CPU0_PE1_SS_C_TXP<7:0>
J 0
(-3410 4410);
DISPLAY 0.680851 (-3410 4410);
PAINT ORANGE (-3410 4410);
WIRE 17 -1 (-2350 4400)(-2350 4375);
WIRE 17 -1 (-2350 3425)(-2350 3275);
WIRE 17 -1 (-2350 4375)(-2350 4175);
WIRE 17 -1 (-2350 4175)(-2350 4025);
WIRE 17 -1 (-2350 3575)(-2350 3425);
WIRE 17 -1 (-2350 3725)(-2350 3575);
WIRE 17 -1 (-2350 4025)(-2350 3875);
WIRE 17 -1 (-2350 3875)(-2350 3725);
WIRE 17 -1 (-2100 2225)(-2100 2075);
WIRE 17 -1 (-2100 2375)(-2100 2225);
WIRE 17 -1 (-2100 2525)(-2100 2375);
WIRE 17 -1 (-2100 2675)(-2100 2525);
WIRE 17 -1 (-2100 2825)(-2100 2675);
WIRE 17 -1 (-2100 3025)(-2100 2825);
WIRE 17 -1 (-2100 3100)(-3450 3100);
FORCEPROP 2 LAST SIG_NAME P3E_CPU0_PE2_SS_C_TXP<7:0>
J 0
(-3410 3110);
DISPLAY 0.680851 (-3410 3110);
PAINT ORANGE (-3410 3110);
WIRE 17 -1 (-2100 3025)(-2100 3100);
WIRE 17 -1 (-2100 3100)(-2100 3125);
WIRE 17 -1 (-2350 2275)(-2350 2125);
WIRE 17 -1 (-2350 2425)(-2350 2275);
WIRE 17 -1 (-2350 2575)(-2350 2425);
WIRE 17 -1 (-2350 2725)(-2350 2575);
WIRE 17 -1 (-2350 2875)(-2350 2725);
WIRE 17 -1 (-3450 3200)(-2350 3200);
FORCEPROP 2 LAST SIG_NAME P3E_CPU0_PE2_SS_C_TXN<7:0>
J 0
(-3410 3210);
DISPLAY 0.680851 (-3410 3210);
PAINT ORANGE (-3410 3210);
WIRE 17 -1 (-2350 3200)(-2350 3175);
WIRE 17 -1 (-2350 2975)(-2350 2875);
WIRE 17 -1 (-2350 2975)(-2350 3175);
WIRE 16 -1 (-1350 3400)(-2250 3400);
WIRE 16 -1 (-2250 4150)(-1350 4150);
WIRE 16 -1 (-1350 3300)(-2000 3300);
WIRE 16 -1 (-650 2050)(-325 2050);
WIRE 16 -1 (-1350 3250)(-2250 3250);
WIRE 16 -1 (-1350 4350)(-2250 4350);
WIRE 3 2175 (-4175 1150)(2025 1150);
WIRE 3 2175 (2025 4875)(2025 1150);
WIRE 3 2175 (-4175 4875)(-4175 1150);
WIRE 3 2175 (-4175 4875)(2025 4875);
WIRE 16 -1 (-2000 2800)(-1350 2800);
WIRE 16 -1 (-3450 1950)(-1350 1950);
FORCEPROP 0 LAST SIG_NAME FM_PRSNT_2_6_N
J 0
(-3360 1960);
DISPLAY 0.617021 (-3360 1960);
PAINT ORANGE (-3360 1960);
WIRE 16 -1 (-650 3500)(-100 3500);
WIRE 16 -1 (-2250 2100)(-1350 2100);
WIRE 16 -1 (-1350 2250)(-2250 2250);
WIRE 16 -1 (-2250 2400)(-1350 2400);
WIRE 16 -1 (-2000 2050)(-1350 2050);
WIRE 16 -1 (-1350 2200)(-2000 2200);
WIRE 16 -1 (-2250 2550)(-1350 2550);
WIRE 16 -1 (-2000 2350)(-1350 2350);
WIRE 16 -1 (-2000 2500)(-1350 2500);
WIRE 16 -1 (-1350 2700)(-2250 2700);
WIRE 16 -1 (-2250 2950)(-1350 2950);
WIRE 16 -1 (-2250 2850)(-1350 2850);
WIRE 16 -1 (-1350 2650)(-2000 2650);
WIRE 16 -1 (-2000 3000)(-1350 3000);
WIRE 16 -1 (-2250 3150)(-1350 3150);
WIRE 16 -1 (-1350 3550)(-2250 3550);
WIRE 16 -1 (-2000 3100)(-1350 3100);
WIRE 16 -1 (-1350 3450)(-2000 3450);
WIRE 16 -1 (-1350 3850)(-2250 3850);
WIRE 16 -1 (-1350 4000)(-2250 4000);
WIRE 16 -1 (-1350 3700)(-2250 3700);
WIRE 16 -1 (-1350 3600)(-2000 3600);
WIRE 16 -1 (-1350 3750)(-2000 3750);
WIRE 16 -1 (-1350 4050)(-2000 4050);
WIRE 16 -1 (-1350 3900)(-2000 3900);
WIRE 16 -1 (-100 2000)(-650 2000);
WIRE 16 -1 (-650 2150)(-325 2150);
WIRE 16 -1 (-650 2500)(-325 2500);
WIRE 16 -1 (-650 2350)(-325 2350);
WIRE 16 -1 (-650 2200)(-100 2200);
WIRE 16 -1 (-650 2300)(-100 2300);
WIRE 16 -1 (-650 2450)(-100 2450);
WIRE 16 -1 (-650 2650)(-325 2650);
WIRE 16 -1 (-650 2800)(-325 2800);
WIRE 16 -1 (-650 2950)(-325 2950);
WIRE 16 -1 (-650 2600)(-100 2600);
WIRE 16 -1 (-650 2750)(-100 2750);
WIRE 16 -1 (-650 2900)(-100 2900);
WIRE 16 -1 (-650 3050)(-100 3050);
WIRE 16 -1 (-650 3250)(-325 3250);
WIRE 16 -1 (-650 3100)(-325 3100);
WIRE 16 -1 (-650 3400)(-325 3400);
WIRE 16 -1 (-650 3550)(-325 3550);
WIRE 16 -1 (-650 3200)(-100 3200);
WIRE 16 -1 (-650 3350)(-100 3350);
WIRE 16 -1 (-650 3700)(-325 3700);
WIRE 16 -1 (-650 4000)(-325 4000);
WIRE 16 -1 (-650 3850)(-325 3850);
WIRE 16 -1 (-650 3650)(-100 3650);
WIRE 16 -1 (-650 3800)(-100 3800);
WIRE 16 -1 (-650 3950)(-100 3950);
WIRE 16 -1 (-1350 4300)(-2000 4300);
WIRE 16 -1 (-2000 4200)(-1350 4200);
WIRE 16 -1 (-650 4300)(-325 4300);
WIRE 16 -1 (-650 4150)(-325 4150);
WIRE 16 -1 (-650 4400)(-325 4400);
WIRE 16 -1 (-650 4100)(-100 4100);
WIRE 16 -1 (-650 4250)(-100 4250);
DOT 1 (-475 4200);
DOT 1 (-1525 4250);
DOT 1 (-1525 4100);
DOT 1 (-475 3900);
DOT 1 (-475 4050);
DOT 1 (-475 3600);
DOT 1 (-475 3750);
DOT 1 (-475 3150);
DOT 1 (-475 3300);
DOT 1 (-475 2850);
DOT 1 (-475 3000);
DOT 1 (-475 2700);
DOT 1 (-475 2550);
DOT 1 (-475 2400);
DOT 1 (-475 2100);
DOT 1 (-475 2250);
DOT 1 (-1525 3950);
DOT 1 (-1525 3650);
DOT 1 (-1525 3800);
DOT 1 (-1525 3350);
DOT 1 (-1525 3500);
DOT 1 (-1525 3200);
DOT 1 (-1525 2900);
DOT 1 (-1525 3050);
DOT 1 (-1525 2600);
DOT 1 (-1525 2750);
DOT 1 (-1525 2450);
DOT 1 (-1525 2300);
DOT 1 (-1525 2150);
DOT 1 (-475 1950);
DOT 1 (-1525 2000);
DOT 1 (-2100 3100);
DOT 1 (-475 3450);
FORCENOTE
ROOM=IO_SLOT
(-5253 678) 0;
DISPLAY LEFT (-5253 678);
DISPLAY 2.510638 (-5253 678);
PAINT PURPLE (-5253 678);
FORCENOTE
TP FAB1 CHANGE PCIE TOPOLOGY 1116
(-1700 1475) 0;
DISPLAY LEFT (-1700 1475);
DISPLAY 1.702128 (-1700 1475);
PAINT RED (-1700 1475);
QUIT
